G04 ================== begin FILE IDENTIFICATION RECORD ==================*
G04 Layout Name:  15126-1b.brd*
G04 Film Name:    TSMD*
G04 File Format:  Gerber RS274X*
G04 File Origin:  Cadence Allegro 16.6-2015-S079*
G04 Origin Date:  Fri Feb 10 17:21:53 2017*
G04 *
G04 Layer:  PIN/PASTEMASK_TOP*
G04 Layer:  PACKAGE GEOMETRY/PASTEMASK_TOP*
G04 Layer:  DRAWING FORMAT/LAYER_PAST_T*
G04 Layer:  VIA CLASS/PASTEMASK_TOP*
G04 Layer:  DRAWING FORMAT/LAYER_PCB_STORY*
G04 Layer:  BOARD GEOMETRY/PANEL_OUTLINE*
G04 *
G04 Offset:    (0.00 0.00)*
G04 Mirror:    No*
G04 Mode:      Positive*
G04 Rotation:  0*
G04 FullContactRelief:  No*
G04 UndefLineWidth:     6.00*
G04 ================== end FILE IDENTIFICATION RECORD ====================*
%FSLAX35Y35*MOIN*%
%IR0*IPPOS*OFA0.00000B0.00000*MIA0B0*SFA1.00000B1.00000*%
%AMMACRO194*
4,1,40,.017,-.013,
.017,.013,
.016939,.013695,
.016759,.014368,
.016464,.015,
.016064,.015571,
.015571,.016064,
.015,.016464,
.014368,.016759,
.013695,.016939,
.013,.017,
-.013,.017,
-.013695,.016939,
-.014368,.016759,
-.015,.016464,
-.015571,.016064,
-.016064,.015571,
-.016464,.015,
-.016759,.014368,
-.016939,.013695,
-.017,.013,
-.017,-.013,
-.016939,-.013695,
-.016759,-.014368,
-.016464,-.015,
-.016064,-.015571,
-.015571,-.016064,
-.015,-.016464,
-.014368,-.016759,
-.013695,-.016939,
-.013,-.017,
.013,-.017,
.013695,-.016939,
.014368,-.016759,
.015,-.016464,
.015571,-.016064,
.016064,-.015571,
.016464,-.015,
.016759,-.014368,
.016939,-.013695,
.017,-.013,
0.0*
%
%ADD194MACRO194*%
%AMMACRO28*
4,1,40,.013,.017,
-.013,.017,
-.013695,.016939,
-.014368,.016759,
-.015,.016464,
-.015571,.016064,
-.016064,.015571,
-.016464,.015,
-.016759,.014368,
-.016939,.013695,
-.017,.013,
-.017,-.013,
-.016939,-.013695,
-.016759,-.014368,
-.016464,-.015,
-.016064,-.015571,
-.015571,-.016064,
-.015,-.016464,
-.014368,-.016759,
-.013695,-.016939,
-.013,-.017,
.013,-.017,
.013695,-.016939,
.014368,-.016759,
.015,-.016464,
.015571,-.016064,
.016064,-.015571,
.016464,-.015,
.016759,-.014368,
.016939,-.013695,
.017,-.013,
.017,.013,
.016939,.013695,
.016759,.014368,
.016464,.015,
.016064,.015571,
.015571,.016064,
.015,.016464,
.014368,.016759,
.013695,.016939,
.013,.017,
0.0*
%
%ADD28MACRO28*%
%AMMACRO125*
4,1,6,-.0425,.1065,
.0145,.1065,
.0145,.0365,
.0425,.0365,
.0425,-.1065,
-.0425,-.1065,
-.0425,.1065,
0.0*
%
%ADD125MACRO125*%
%AMMACRO263*
4,1,21,.006,.015,
.006,-.009,
.005909,-.010042,
.005638,-.011052,
.005196,-.012,
.004596,-.012857,
.003857,-.013596,
.003,-.014196,
.002052,-.014638,
.001042,-.014909,
0.0,-.015,
-.001042,-.014909,
-.002052,-.014638,
-.003,-.014196,
-.003857,-.013596,
-.004596,-.012857,
-.005196,-.012,
-.005638,-.011052,
-.005909,-.010042,
-.006,-.009,
-.006,.015,
.006,.015,
0.0*
%
%ADD263MACRO263*%
%ADD100O,.062X.111*%
%ADD110R,.02X.004*%
%AMMACRO108*
21,1,.004,.02,0.0,0.0,45.*%
%ADD108MACRO108*%
%ADD306R,.05X.115*%
%ADD109R,.004X.02*%
%ADD13R,.09X.12*%
%AMMACRO291*
4,1,12,.0325,.0195,
-.0325,.0195,
-.0325,-.0195,
-.0195,-.0195,
-.0195,.0005,
-.0065,.0005,
-.0065,-.0195,
.0065,-.0195,
.0065,.0005,
.0195,.0005,
.0195,-.0195,
.0325,-.0195,
.0325,.0195,
0.0*
%
%ADD291MACRO291*%
%ADD93R,.12X.09*%
%ADD82R,.135X.031*%
%ADD287R,.108X.04*%
%ADD257R,.055X.13*%
%ADD89R,.11X.039*%
%ADD67R,.031X.135*%
%ADD274R,.138X.02*%
%AMMACRO78*
4,1,21,.006,-.014,
-.006,-.014,
-.006,.008,
-.005909,.009042,
-.005638,.010052,
-.005196,.011,
-.004596,.011857,
-.003857,.012596,
-.003,.013196,
-.002052,.013638,
-.001042,.013909,
0.0,.014,
.001042,.013909,
.002052,.013638,
.003,.013196,
.003857,.012596,
.004596,.011857,
.005196,.011,
.005638,.010052,
.005909,.009042,
.006,.008,
.006,-.014,
0.0*
%
%ADD78MACRO78*%
%ADD48R,.134X.024*%
%ADD33R,.024X.171*%
%ADD11R,.053X.106*%
%AMMACRO242*
4,1,4,.00002,-.01131,
-.01131,-.00002,
-.00002,.01131,
.01131,.00002,
.00002,-.01131,
0.0*
%
%ADD242MACRO242*%
%ADD213R,.171X.024*%
%AMMACRO204*
4,1,40,-.007,-.008,
-.007174,-.007985,
-.007342,-.00794,
-.0075,-.007866,
-.007643,-.007766,
-.007766,-.007643,
-.007866,-.0075,
-.00794,-.007342,
-.007985,-.007174,
-.008,-.007,
-.008,.007,
-.007985,.007174,
-.00794,.007342,
-.007866,.0075,
-.007766,.007643,
-.007643,.007766,
-.0075,.007866,
-.007342,.00794,
-.007174,.007985,
-.007,.008,
.007,.008,
.007174,.007985,
.007342,.00794,
.0075,.007866,
.007643,.007766,
.007766,.007643,
.007866,.0075,
.00794,.007342,
.007985,.007174,
.008,.007,
.008,-.007,
.007985,-.007174,
.00794,-.007342,
.007866,-.0075,
.007766,-.007643,
.007643,-.007766,
.0075,-.007866,
.007342,-.00794,
.007174,-.007985,
.007,-.008,
-.007,-.008,
0.0*
%
%ADD204MACRO204*%
%AMMACRO264*
4,1,21,.015,-.006,
-.009,-.006,
-.010042,-.005909,
-.011052,-.005638,
-.012,-.005196,
-.012857,-.004596,
-.013596,-.003857,
-.014196,-.003,
-.014638,-.002052,
-.014909,-.001042,
-.015,0.0,
-.014909,.001042,
-.014638,.002052,
-.014196,.003,
-.013596,.003857,
-.012857,.004596,
-.012,.005196,
-.011052,.005638,
-.010042,.005909,
-.009,.006,
.015,.006,
.015,-.006,
0.0*
%
%ADD264MACRO264*%
%ADD20C,.04*%
%ADD294R,.014X.008*%
%ADD186C,.014*%
%AMMACRO175*
4,1,4,.008,-.008,
-.008,-.008,
-.008,.008,
.008,.008,
.008,-.008,
0.0*
%
%ADD175MACRO175*%
%AMMACRO122*
4,1,4,.01131,0.0,
0.0,-.01131,
-.01131,0.0,
0.0,.01131,
.01131,0.0,
0.0*
%
%ADD122MACRO122*%
%AMMACRO243*
4,1,4,.00801,-.00798,
-.00798,-.00801,
-.00801,.00798,
.00798,.00801,
.00801,-.00798,
0.0*
%
%ADD243MACRO243*%
%ADD200R,.108X.047*%
%AMMACRO193*
4,1,4,.00226,-.01108,
-.01108,-.00226,
-.00226,.01108,
.01108,.00226,
.00226,-.01108,
0.0*
%
%ADD193MACRO193*%
%ADD181R,.063X.118*%
%AMMACRO95*
4,1,4,.0085,-.0085,
-.0085,-.0085,
-.0085,.0085,
.0085,.0085,
.0085,-.0085,
0.0*
%
%ADD95MACRO95*%
%AMMACRO62*
4,1,4,0.0,-.01131,
-.01131,0.0,
0.0,.01131,
.01131,0.0,
0.0,-.01131,
0.0*
%
%ADD62MACRO62*%
%ADD49C,.06*%
%ADD47R,.134X.047*%
%AMMACRO40*
4,1,4,.01202,0.0,
0.0,-.01202,
-.01202,0.0,
0.0,.01202,
.01202,0.0,
0.0*
%
%ADD40MACRO40*%
%ADD235C,.016*%
%AMMACRO178*
4,1,4,.00654,-.00923,
-.00923,-.00654,
-.00654,.00923,
.00923,.00654,
.00654,-.00923,
0.0*
%
%ADD178MACRO178*%
%AMMACRO126*
4,1,4,0.0,-.01202,
-.01202,0.0,
0.0,.01202,
.01202,0.0,
0.0,-.01202,
0.0*
%
%ADD126MACRO126*%
%ADD107C,.025*%
%AMMACRO275*
4,1,6,-.0475,-.0155,
-.0475,.0445,
.0475,.0445,
.0475,-.0445,
-.0235,-.0445,
-.0235,-.0155,
-.0475,-.0155,
0.0*
%
%ADD275MACRO275*%
%ADD266R,.094X.207*%
%ADD224C,.026*%
%ADD285C,.045*%
%ADD232C,.054*%
%AMMACRO207*
4,1,40,.0007,-.0099,
.000566,-.010011,
.000416,-.010097,
.000252,-.010155,
.000081,-.010184,
-.000092,-.010183,
-.000263,-.010152,
-.000426,-.010092,
-.000575,-.010005,
-.0007,-.0099,
-.0099,-.0007,
-.010011,-.000566,
-.010097,-.000416,
-.010155,-.000252,
-.010184,-.000081,
-.010183,.000092,
-.010152,.000263,
-.010092,.000426,
-.010005,.000575,
-.0099,.0007,
-.0007,.0099,
-.000566,.010011,
-.000416,.010097,
-.000252,.010155,
-.000081,.010184,
.000092,.010183,
.000263,.010152,
.000426,.010092,
.000575,.010005,
.0007,.0099,
.0099,.0007,
.010011,.000566,
.010097,.000416,
.010155,.000252,
.010184,.000081,
.010183,-.000092,
.010152,-.000263,
.010092,-.000426,
.010005,-.000575,
.0099,-.0007,
.0007,-.0099,
0.0*
%
%ADD207MACRO207*%
%ADD206C,.018*%
%AMMACRO164*
4,1,4,.00681,-.00903,
-.00903,-.00681,
-.00681,.00903,
.00903,.00681,
.00681,-.00903,
0.0*
%
%ADD164MACRO164*%
%ADD304C,.055*%
%AMMACRO262*
4,1,21,-.015,.006,
.009,.006,
.010042,.005909,
.011052,.005638,
.012,.005196,
.012857,.004596,
.013596,.003857,
.014196,.003,
.014638,.002052,
.014909,.001042,
.015,0.0,
.014909,-.001042,
.014638,-.002052,
.014196,-.003,
.013596,-.003857,
.012857,-.004596,
.012,-.005196,
.011052,-.005638,
.010042,-.005909,
.009,-.006,
-.015,-.006,
-.015,.006,
0.0*
%
%ADD262MACRO262*%
%AMMACRO209*
4,1,40,-.0099,-.0007,
-.010011,-.000566,
-.010097,-.000416,
-.010155,-.000252,
-.010184,-.000081,
-.010183,.000092,
-.010152,.000263,
-.010092,.000426,
-.010005,.000575,
-.0099,.0007,
-.0007,.0099,
-.000566,.010011,
-.000416,.010097,
-.000252,.010155,
-.000081,.010184,
.000092,.010183,
.000263,.010152,
.000426,.010092,
.000575,.010005,
.0007,.0099,
.0099,.0007,
.010011,.000566,
.010097,.000416,
.010155,.000252,
.010184,.000081,
.010183,-.000092,
.010152,-.000263,
.010092,-.000426,
.010005,-.000575,
.0099,-.0007,
.0007,-.0099,
.000566,-.010011,
.000416,-.010097,
.000252,-.010155,
.000081,-.010184,
-.000092,-.010183,
-.000263,-.010152,
-.000426,-.010092,
-.000575,-.010005,
-.0007,-.0099,
-.0099,-.0007,
0.0*
%
%ADD209MACRO209*%
%ADD182C,.064*%
%ADD96C,.019*%
%ADD289C,.047*%
%ADD276R,.013X.013*%
%AMMACRO195*
4,1,21,.01,.004,
.010695,.003939,
.011368,.003759,
.012,.003464,
.012571,.003064,
.013064,.002571,
.013464,.002,
.013759,.001368,
.013939,.000695,
.014,0.0,
.013939,-.000695,
.013759,-.001368,
.013464,-.002,
.013064,-.002571,
.012571,-.003064,
.012,-.003464,
.011368,-.003759,
.010695,-.003939,
.01,-.004,
-.014,-.004,
-.014,.004,
.01,.004,
0.0*
%
%ADD195MACRO195*%
%AMMACRO160*
4,1,4,.00801,-.00798,
.00798,.00801,
-.00801,.00798,
-.00798,-.00801,
.00801,-.00798,
0.0*
%
%ADD160MACRO160*%
%ADD92R,.075X.165*%
%AMMACRO79*
4,1,21,-.014,-.006,
-.014,.006,
.008,.006,
.009042,.005909,
.010052,.005638,
.011,.005196,
.011857,.004596,
.012596,.003857,
.013196,.003,
.013638,.002052,
.013909,.001042,
.014,0.0,
.013909,-.001042,
.013638,-.002052,
.013196,-.003,
.012596,-.003857,
.011857,-.004596,
.011,-.005196,
.010052,-.005638,
.009042,-.005909,
.008,-.006,
-.014,-.006,
0.0*
%
%ADD79MACRO79*%
%ADD267R,.05X.05*%
%AMMACRO261*
4,1,21,-.006,-.015,
-.006,.009,
-.005909,.010042,
-.005638,.011052,
-.005196,.012,
-.004596,.012857,
-.003857,.013596,
-.003,.014196,
-.002052,.014638,
-.001042,.014909,
0.0,.015,
.001042,.014909,
.002052,.014638,
.003,.014196,
.003857,.013596,
.004596,.012857,
.005196,.012,
.005638,.011052,
.005909,.010042,
.006,.009,
.006,-.015,
-.006,-.015,
0.0*
%
%ADD261MACRO261*%
%AMMACRO83*
4,1,21,.004,-.01,
.003939,-.010695,
.003759,-.011368,
.003464,-.012,
.003064,-.012571,
.002571,-.013064,
.002,-.013464,
.001368,-.013759,
.000695,-.013939,
0.0,-.014,
-.000695,-.013939,
-.001368,-.013759,
-.002,-.013464,
-.002571,-.013064,
-.003064,-.012571,
-.003464,-.012,
-.003759,-.011368,
-.003939,-.010695,
-.004,-.01,
-.004,.014,
.004,.014,
.004,-.01,
0.0*
%
%ADD83MACRO83*%
%ADD63C,.039*%
%ADD88R,.06X.06*%
%ADD19C,.086*%
%ADD312R,.035X.035*%
%ADD286R,.045X.045*%
%ADD247R,.054X.054*%
%AMMACRO162*
4,1,4,.0042,-.0105,
.0105,.0042,
-.0042,.0105,
-.0105,-.0042,
.0042,-.0105,
0.0*
%
%ADD162MACRO162*%
%ADD305R,.055X.055*%
%ADD183R,.064X.064*%
%AMMACRO81*
4,1,21,.014,.006,
.014,-.006,
-.008,-.006,
-.009042,-.005909,
-.010052,-.005638,
-.011,-.005196,
-.011857,-.004596,
-.012596,-.003857,
-.013196,-.003,
-.013638,-.002052,
-.013909,-.001042,
-.014,0.0,
-.013909,.001042,
-.013638,.002052,
-.013196,.003,
-.012596,.003857,
-.011857,.004596,
-.011,.005196,
-.010052,.005638,
-.009042,.005909,
-.008,.006,
.014,.006,
0.0*
%
%ADD81MACRO81*%
%ADD290R,.047X.047*%
%AMMACRO163*
4,1,4,.00645,-.00929,
.00929,.00645,
-.00645,.00929,
-.00929,-.00645,
.00645,-.00929,
0.0*
%
%ADD163MACRO163*%
%AMMACRO159*
4,1,4,.00627,-.00942,
.00942,.00627,
-.00627,.00942,
-.00942,-.00627,
.00627,-.00942,
0.0*
%
%ADD159MACRO159*%
%AMMACRO133*
4,1,40,.011,-.007,
.011,.007,
.010939,.007695,
.010759,.008368,
.010464,.009,
.010064,.009571,
.009571,.010064,
.009,.010464,
.008368,.010759,
.007695,.010939,
.007,.011,
-.007,.011,
-.007695,.010939,
-.008368,.010759,
-.009,.010464,
-.009571,.010064,
-.010064,.009571,
-.010464,.009,
-.010759,.008368,
-.010939,.007695,
-.011,.007,
-.011,-.007,
-.010939,-.007695,
-.010759,-.008368,
-.010464,-.009,
-.010064,-.009571,
-.009571,-.010064,
-.009,-.010464,
-.008368,-.010759,
-.007695,-.010939,
-.007,-.011,
.007,-.011,
.007695,-.010939,
.008368,-.010759,
.009,-.010464,
.009571,-.010064,
.010064,-.009571,
.010464,-.009,
.010759,-.008368,
.010939,-.007695,
.011,-.007,
0.0*
%
%ADD133MACRO133*%
%AMMACRO21*
4,1,40,.007,.011,
-.007,.011,
-.007695,.010939,
-.008368,.010759,
-.009,.010464,
-.009571,.010064,
-.010064,.009571,
-.010464,.009,
-.010759,.008368,
-.010939,.007695,
-.011,.007,
-.011,-.007,
-.010939,-.007695,
-.010759,-.008368,
-.010464,-.009,
-.010064,-.009571,
-.009571,-.010064,
-.009,-.010464,
-.008368,-.010759,
-.007695,-.010939,
-.007,-.011,
.007,-.011,
.007695,-.010939,
.008368,-.010759,
.009,-.010464,
.009571,-.010064,
.010064,-.009571,
.010464,-.009,
.010759,-.008368,
.010939,-.007695,
.011,-.007,
.011,.007,
.010939,.007695,
.010759,.008368,
.010464,.009,
.010064,.009571,
.009571,.010064,
.009,.010464,
.008368,.010759,
.007695,.010939,
.007,.011,
0.0*
%
%ADD21MACRO21*%
%AMMACRO80*
4,1,21,-.006,.014,
.006,.014,
.006,-.008,
.005909,-.009042,
.005638,-.010052,
.005196,-.011,
.004596,-.011857,
.003857,-.012596,
.003,-.013196,
.002052,-.013638,
.001042,-.013909,
0.0,-.014,
-.001042,-.013909,
-.002052,-.013638,
-.003,-.013196,
-.003857,-.012596,
-.004596,-.011857,
-.005196,-.011,
-.005638,-.010052,
-.005909,-.009042,
-.006,-.008,
-.006,.014,
0.0*
%
%ADD80MACRO80*%
%ADD64R,.039X.039*%
%AMMACRO196*
4,1,21,.004,-.01,
.003939,-.010695,
.003759,-.011368,
.003464,-.012,
.003064,-.012571,
.002571,-.013064,
.002,-.013464,
.001368,-.013759,
.000695,-.013939,
0.0,-.014,
-.000695,-.013939,
-.001368,-.013759,
-.002,-.013464,
-.002571,-.013064,
-.003064,-.012571,
-.003464,-.012,
-.003759,-.011368,
-.003939,-.010695,
-.004,-.01,
-.004,.014,
.004,.014,
.004,-.01,
0.0*
%
%ADD196MACRO196*%
%AMMACRO84*
4,1,21,-.01,-.004,
-.010695,-.003939,
-.011368,-.003759,
-.012,-.003464,
-.012571,-.003064,
-.013064,-.002571,
-.013464,-.002,
-.013759,-.001368,
-.013939,-.000695,
-.014,0.0,
-.013939,.000695,
-.013759,.001368,
-.013464,.002,
-.013064,.002571,
-.012571,.003064,
-.012,.003464,
-.011368,.003759,
-.010695,.003939,
-.01,.004,
.014,.004,
.014,-.004,
-.01,-.004,
0.0*
%
%ADD84MACRO84*%
%AMMACRO23*
4,1,40,-.012,.008,
-.012,-.008,
-.011939,-.008695,
-.011759,-.009368,
-.011464,-.01,
-.011064,-.010571,
-.010571,-.011064,
-.01,-.011464,
-.009368,-.011759,
-.008695,-.011939,
-.008,-.012,
.008,-.012,
.008695,-.011939,
.009368,-.011759,
.01,-.011464,
.010571,-.011064,
.011064,-.010571,
.011464,-.01,
.011759,-.009368,
.011939,-.008695,
.012,-.008,
.012,.008,
.011939,.008695,
.011759,.009368,
.011464,.01,
.011064,.010571,
.010571,.011064,
.01,.011464,
.009368,.011759,
.008695,.011939,
.008,.012,
-.008,.012,
-.008695,.011939,
-.009368,.011759,
-.01,.011464,
-.010571,.011064,
-.011064,.010571,
-.011464,.01,
-.011759,.009368,
-.011939,.008695,
-.012,.008,
0.0*
%
%ADD23MACRO23*%
%AMMACRO127*
4,1,40,-.013,-.017,
.013,-.017,
.013695,-.016939,
.014368,-.016759,
.015,-.016464,
.015571,-.016064,
.016064,-.015571,
.016464,-.015,
.016759,-.014368,
.016939,-.013695,
.017,-.013,
.017,.013,
.016939,.013695,
.016759,.014368,
.016464,.015,
.016064,.015571,
.015571,.016064,
.015,.016464,
.014368,.016759,
.013695,.016939,
.013,.017,
-.013,.017,
-.013695,.016939,
-.014368,.016759,
-.015,.016464,
-.015571,.016064,
-.016064,.015571,
-.016464,.015,
-.016759,.014368,
-.016939,.013695,
-.017,.013,
-.017,-.013,
-.016939,-.013695,
-.016759,-.014368,
-.016464,-.015,
-.016064,-.015571,
-.015571,-.016064,
-.015,-.016464,
-.014368,-.016759,
-.013695,-.016939,
-.013,-.017,
0.0*
%
%ADD127MACRO127*%
%AMMACRO254*
4,1,40,-.017,.013,
-.017,-.013,
-.016939,-.013695,
-.016759,-.014368,
-.016464,-.015,
-.016064,-.015571,
-.015571,-.016064,
-.015,-.016464,
-.014368,-.016759,
-.013695,-.016939,
-.013,-.017,
.013,-.017,
.013695,-.016939,
.014368,-.016759,
.015,-.016464,
.015571,-.016064,
.016064,-.015571,
.016464,-.015,
.016759,-.014368,
.016939,-.013695,
.017,-.013,
.017,.013,
.016939,.013695,
.016759,.014368,
.016464,.015,
.016064,.015571,
.015571,.016064,
.015,.016464,
.014368,.016759,
.013695,.016939,
.013,.017,
-.013,.017,
-.013695,.016939,
-.014368,.016759,
-.015,.016464,
-.015571,.016064,
-.016064,.015571,
-.016464,.015,
-.016759,.014368,
-.016939,.013695,
-.017,.013,
0.0*
%
%ADD254MACRO254*%
%AMMACRO198*
4,1,21,-.004,.01,
-.003939,.010695,
-.003759,.011368,
-.003464,.012,
-.003064,.012571,
-.002571,.013064,
-.002,.013464,
-.001368,.013759,
-.000695,.013939,
0.0,.014,
.000695,.013939,
.001368,.013759,
.002,.013464,
.002571,.013064,
.003064,.012571,
.003464,.012,
.003759,.011368,
.003939,.010695,
.004,.01,
.004,-.014,
-.004,-.014,
-.004,.01,
0.0*
%
%ADD198MACRO198*%
%AMMACRO86*
4,1,21,.01,.004,
.010695,.003939,
.011368,.003759,
.012,.003464,
.012571,.003064,
.013064,.002571,
.013464,.002,
.013759,.001368,
.013939,.000695,
.014,0.0,
.013939,-.000695,
.013759,-.001368,
.013464,-.002,
.013064,-.002571,
.012571,-.003064,
.012,-.003464,
.011368,-.003759,
.010695,-.003939,
.01,-.004,
-.014,-.004,
-.014,.004,
.01,.004,
0.0*
%
%ADD86MACRO86*%
%AMMACRO197*
4,1,21,-.01,-.004,
-.010695,-.003939,
-.011368,-.003759,
-.012,-.003464,
-.012571,-.003064,
-.013064,-.002571,
-.013464,-.002,
-.013759,-.001368,
-.013939,-.000695,
-.014,0.0,
-.013939,.000695,
-.013759,.001368,
-.013464,.002,
-.013064,.002571,
-.012571,.003064,
-.012,.003464,
-.011368,.003759,
-.010695,.003939,
-.01,.004,
.014,.004,
.014,-.004,
-.01,-.004,
0.0*
%
%ADD197MACRO197*%
%AMMACRO85*
4,1,21,-.004,.01,
-.003939,.010695,
-.003759,.011368,
-.003464,.012,
-.003064,.012571,
-.002571,.013064,
-.002,.013464,
-.001368,.013759,
-.000695,.013939,
0.0,.014,
.000695,.013939,
.001368,.013759,
.002,.013464,
.002571,.013064,
.003064,.012571,
.003464,.012,
.003759,.011368,
.003939,.010695,
.004,.01,
.004,-.014,
-.004,-.014,
-.004,.01,
0.0*
%
%ADD85MACRO85*%
%AMMACRO298*
4,1,4,.01131,-.00003,
-.00003,-.01131,
-.01131,.00003,
.00003,.01131,
.01131,-.00003,
0.0*
%
%ADD298MACRO298*%
%AMMACRO134*
4,1,40,.011,-.007,
.011,.007,
.010939,.007695,
.010759,.008368,
.010464,.009,
.010064,.009571,
.009571,.010064,
.009,.010464,
.008368,.010759,
.007695,.010939,
.007,.011,
-.007,.011,
-.007695,.010939,
-.008368,.010759,
-.009,.010464,
-.009571,.010064,
-.010064,.009571,
-.010464,.009,
-.010759,.008368,
-.010939,.007695,
-.011,.007,
-.011,-.007,
-.010939,-.007695,
-.010759,-.008368,
-.010464,-.009,
-.010064,-.009571,
-.009571,-.010064,
-.009,-.010464,
-.008368,-.010759,
-.007695,-.010939,
-.007,-.011,
.007,-.011,
.007695,-.010939,
.008368,-.010759,
.009,-.010464,
.009571,-.010064,
.010064,-.009571,
.010464,-.009,
.010759,-.008368,
.010939,-.007695,
.011,-.007,
0.0*
%
%ADD134MACRO134*%
%AMMACRO22*
4,1,40,.007,.011,
-.007,.011,
-.007695,.010939,
-.008368,.010759,
-.009,.010464,
-.009571,.010064,
-.010064,.009571,
-.010464,.009,
-.010759,.008368,
-.010939,.007695,
-.011,.007,
-.011,-.007,
-.010939,-.007695,
-.010759,-.008368,
-.010464,-.009,
-.010064,-.009571,
-.009571,-.010064,
-.009,-.010464,
-.008368,-.010759,
-.007695,-.010939,
-.007,-.011,
.007,-.011,
.007695,-.010939,
.008368,-.010759,
.009,-.010464,
.009571,-.010064,
.010064,-.009571,
.010464,-.009,
.010759,-.008368,
.010939,-.007695,
.011,-.007,
.011,.007,
.010939,.007695,
.010759,.008368,
.010464,.009,
.010064,.009571,
.009571,.010064,
.009,.010464,
.008368,.010759,
.007695,.010939,
.007,.011,
0.0*
%
%ADD22MACRO22*%
%ADD104R,.12X.1*%
%ADD114R,.1X.12*%
%AMMACRO237*
4,1,13,.05895,-.0275,
.055324,-.025079,
.051332,-.023324,
.047096,-.022289,
.042745,-.022006,
.03841,-.022482,
.034225,-.023704,
.030315,-.025634,
.02765,-.0275,
-.115,-.0275,
-.115,.0275,
.115,.0275,
.115,-.0275,
.05895,-.0275,
0.0*
%
%ADD237MACRO237*%
%AMMACRO24*
4,1,40,-.012,.008,
-.012,-.008,
-.011939,-.008695,
-.011759,-.009368,
-.011464,-.01,
-.011064,-.010571,
-.010571,-.011064,
-.01,-.011464,
-.009368,-.011759,
-.008695,-.011939,
-.008,-.012,
.008,-.012,
.008695,-.011939,
.009368,-.011759,
.01,-.011464,
.010571,-.011064,
.011064,-.010571,
.011464,-.01,
.011759,-.009368,
.011939,-.008695,
.012,-.008,
.012,.008,
.011939,.008695,
.011759,.009368,
.011464,.01,
.011064,.010571,
.010571,.011064,
.01,.011464,
.009368,.011759,
.008695,.011939,
.008,.012,
-.008,.012,
-.008695,.011939,
-.009368,.011759,
-.01,.011464,
-.010571,.011064,
-.011064,.010571,
-.011464,.01,
-.011759,.009368,
-.011939,.008695,
-.012,.008,
0.0*
%
%ADD24MACRO24*%
%AMMACRO301*
4,1,11,.016,-.006,
-.016,-.006,
-.016,.006,
.01122,.006,
.011821,.004838,
.012489,.003712,
.013222,.002627,
.014016,.001587,
.014869,.000594,
.015779,-.000347,
.016,-.00056,
.016,-.006,
0.0*
%
%ADD301MACRO301*%
%AMMACRO128*
4,1,40,-.013,-.017,
.013,-.017,
.013695,-.016939,
.014368,-.016759,
.015,-.016464,
.015571,-.016064,
.016064,-.015571,
.016464,-.015,
.016759,-.014368,
.016939,-.013695,
.017,-.013,
.017,.013,
.016939,.013695,
.016759,.014368,
.016464,.015,
.016064,.015571,
.015571,.016064,
.015,.016464,
.014368,.016759,
.013695,.016939,
.013,.017,
-.013,.017,
-.013695,.016939,
-.014368,.016759,
-.015,.016464,
-.015571,.016064,
-.016064,.015571,
-.016464,.015,
-.016759,.014368,
-.016939,.013695,
-.017,.013,
-.017,-.013,
-.016939,-.013695,
-.016759,-.014368,
-.016464,-.015,
-.016064,-.015571,
-.015571,-.016064,
-.015,-.016464,
-.014368,-.016759,
-.013695,-.016939,
-.013,-.017,
0.0*
%
%ADD128MACRO128*%
%AMMACRO255*
4,1,40,-.017,.013,
-.017,-.013,
-.016939,-.013695,
-.016759,-.014368,
-.016464,-.015,
-.016064,-.015571,
-.015571,-.016064,
-.015,-.016464,
-.014368,-.016759,
-.013695,-.016939,
-.013,-.017,
.013,-.017,
.013695,-.016939,
.014368,-.016759,
.015,-.016464,
.015571,-.016064,
.016064,-.015571,
.016464,-.015,
.016759,-.014368,
.016939,-.013695,
.017,-.013,
.017,.013,
.016939,.013695,
.016759,.014368,
.016464,.015,
.016064,.015571,
.015571,.016064,
.015,.016464,
.014368,.016759,
.013695,.016939,
.013,.017,
-.013,.017,
-.013695,.016939,
-.014368,.016759,
-.015,.016464,
-.015571,.016064,
-.016064,.015571,
-.016464,.015,
-.016759,.014368,
-.016939,.013695,
-.017,.013,
0.0*
%
%ADD255MACRO255*%
%AMMACRO69*
4,1,8,.0825,-.065,
.0825,.065,
-.0175,.065,
-.0175,.087,
-.0825,.087,
-.0825,-.087,
-.0175,-.087,
-.0175,-.065,
.0825,-.065,
0.0*
%
%ADD69MACRO69*%
%AMMACRO32*
4,1,6,.0425,-.1065,
-.0145,-.1065,
-.0145,-.0365,
-.0425,-.0365,
-.0425,.1065,
.0425,.1065,
.0425,-.1065,
0.0*
%
%ADD32MACRO32*%
%ADD17R,.02X.02*%
%AMMACRO212*
4,1,6,-.1065,-.0425,
-.1065,.0145,
-.0365,.0145,
-.0365,.0425,
.1065,.0425,
.1065,-.0425,
-.1065,-.0425,
0.0*
%
%ADD212MACRO212*%
%ADD16R,.02X.02*%
%ADD308R,.032X.01*%
%ADD240R,.012X.03*%
%ADD239R,.03X.012*%
%AMMACRO120*
4,1,21,.0095,.0055,
.010455,.005416,
.011381,.005168,
.01225,.004763,
.013035,.004213,
.013713,.003535,
.014263,.00275,
.014668,.001881,
.014916,.000955,
.015,0.0,
.014916,-.000955,
.014668,-.001881,
.014263,-.00275,
.013713,-.003535,
.013035,-.004213,
.01225,-.004763,
.011381,-.005168,
.010455,-.005416,
.0095,-.0055,
-.015,-.0055,
-.015,.0055,
.0095,.0055,
0.0*
%
%ADD120MACRO120*%
%ADD34R,.014X.02*%
%ADD311R,.05X.03*%
%ADD297R,.032X.012*%
%AMMACRO258*
4,1,12,-.0195,.0325,
-.0195,-.0325,
.0195,-.0325,
.0195,-.0195,
-.0005,-.0195,
-.0005,-.0065,
.0195,-.0065,
.0195,.0065,
-.0005,.0065,
-.0005,.0195,
.0195,.0195,
.0195,.0325,
-.0195,.0325,
0.0*
%
%ADD258MACRO258*%
%ADD214R,.02X.014*%
%AMMACRO130*
4,1,21,.015,-.006,
-.009,-.006,
-.010042,-.005909,
-.011052,-.005638,
-.012,-.005196,
-.012857,-.004596,
-.013596,-.003857,
-.014196,-.003,
-.014638,-.002052,
-.014909,-.001042,
-.015,0.0,
-.014909,.001042,
-.014638,.002052,
-.014196,.003,
-.013596,.003857,
-.012857,.004596,
-.012,.005196,
-.011052,.005638,
-.010042,.005909,
-.009,.006,
.015,.006,
.015,-.006,
0.0*
%
%ADD130MACRO130*%
%ADD106R,.125X.14*%
%ADD268R,.03X.05*%
%ADD252R,.102X.145*%
%ADD228R,.011X.033*%
%ADD227R,.033X.011*%
%AMMACRO219*
4,1,21,-.006,-.015,
-.006,.009,
-.005909,.010042,
-.005638,.011052,
-.005196,.012,
-.004596,.012857,
-.003857,.013596,
-.003,.014196,
-.002052,.014638,
-.001042,.014909,
0.0,.015,
.001042,.014909,
.002052,.014638,
.003,.014196,
.003857,.013596,
.004596,.012857,
.005196,.012,
.005638,.011052,
.005909,.010042,
.006,.009,
.006,-.015,
-.006,-.015,
0.0*
%
%ADD219MACRO219*%
%AMMACRO205*
4,1,40,.0078,-.0068,
.007775,-.006982,
.00772,-.007156,
.007634,-.007318,
.007522,-.007463,
.007387,-.007586,
.007232,-.007684,
.007062,-.007754,
.006883,-.007793,
.0068,-.0078,
-.0068,-.0078,
-.006982,-.007775,
-.007156,-.00772,
-.007318,-.007634,
-.007463,-.007522,
-.007586,-.007387,
-.007684,-.007232,
-.007754,-.007062,
-.007793,-.006883,
-.0078,-.0068,
-.0078,.0068,
-.007775,.006982,
-.00772,.007156,
-.007634,.007318,
-.007522,.007463,
-.007387,.007586,
-.007232,.007684,
-.007062,.007754,
-.006883,.007793,
-.0068,.0078,
.0068,.0078,
.006982,.007775,
.007156,.00772,
.007318,.007634,
.007463,.007522,
.007586,.007387,
.007684,.007232,
.007754,.007062,
.007793,.006883,
.0078,.0068,
.0078,-.0068,
0.0*
%
%ADD205MACRO205*%
%ADD50R,.04X.05*%
%ADD201R,.061X.012*%
%ADD91R,.02X.071*%
%ADD75R,.015X.04*%
%ADD74R,.05X.04*%
%ADD278R,.071X.02*%
%ADD251R,.012X.026*%
%ADD211R,.105X.145*%
%ADD72R,.012X.035*%
%ADD71R,.02X.045*%
%ADD70R,.06X.04*%
%ADD66R,.04X.015*%
%ADD46R,.015X.05*%
%ADD37R,.01X.028*%
%ADD36R,.028X.01*%
%ADD18R,.035X.03*%
%ADD14R,.04X.016*%
%ADD303R,.05X.015*%
%ADD293R,.026X.012*%
%AMMACRO269*
21,1,.011,.09,0.0,0.0,90.001*%
%ADD269MACRO269*%
%ADD218R,.028X.01*%
%ADD217R,.01X.028*%
%ADD135R,.045X.02*%
%ADD116R,.012X.027*%
%ADD65R,.016X.04*%
%ADD60C,.111*%
%ADD41R,.03X.035*%
%ADD38R,.145X.105*%
%ADD15R,.014X.06*%
%ADD307R,.071X.032*%
%ADD300R,.028X.012*%
%ADD296R,.061X.024*%
%ADD222R,.02X.047*%
%ADD117R,.027X.012*%
%ADD73R,.012X.037*%
%ADD284O,.07X.046*%
%AMMACRO283*
4,1,4,.008,.008,
.008,-.008,
-.008,-.008,
-.008,.008,
.008,.008,
0.0*
%
%ADD283MACRO283*%
%AMMACRO280*
4,1,21,-.0225,.006,
.0165,.006,
.017542,.005909,
.018552,.005638,
.0195,.005196,
.020357,.004596,
.021096,.003857,
.021696,.003,
.022138,.002052,
.022409,.001042,
.0225,0.0,
.022409,-.001042,
.022138,-.002052,
.021696,-.003,
.021096,-.003857,
.020357,-.004596,
.0195,-.005196,
.018552,-.005638,
.017542,-.005909,
.0165,-.006,
-.0225,-.006,
-.0225,.006,
0.0*
%
%ADD280MACRO280*%
%ADD241R,.045X.041*%
%AMMACRO230*
4,1,4,-.01131,0.0,
0.0,.01131,
.01131,0.0,
0.0,-.01131,
-.01131,0.0,
0.0*
%
%ADD230MACRO230*%
%AMMACRO223*
4,1,4,-.008,.008,
.008,.008,
.008,-.008,
-.008,-.008,
-.008,.008,
0.0*
%
%ADD223MACRO223*%
%ADD184R,.02X.047*%
%AMMACRO180*
4,1,4,0.0,.01131,
.01131,0.0,
0.0,-.01131,
-.01131,0.0,
0.0,.01131,
0.0*
%
%ADD180MACRO180*%
%AMMACRO156*
4,1,4,-.00513,-.01008,
-.01008,.00513,
.00513,.01008,
.01008,-.00513,
-.00513,-.01008,
0.0*
%
%ADD156MACRO156*%
%ADD94R,.05X.018*%
%AMMACRO87*
4,1,4,-.008,-.008,
-.008,.008,
.008,.008,
.008,-.008,
-.008,-.008,
0.0*
%
%ADD87MACRO87*%
%ADD68R,.065X.02*%
%ADD44C,.14*%
%ADD256R,.02X.094*%
%AMMACRO246*
4,1,4,-.00798,-.00801,
-.00801,.00798,
.00798,.00801,
.00801,-.00798,
-.00798,-.00801,
0.0*
%
%ADD246MACRO246*%
%AMMACRO236*
4,1,13,.05895,.0275,
.055324,.025079,
.051332,.023324,
.047096,.022289,
.042745,.022006,
.03841,.022482,
.034225,.023704,
.030315,.025634,
.02765,.0275,
-.115,.0275,
-.115,-.0275,
.115,-.0275,
.115,.0275,
.05895,.0275,
0.0*
%
%ADD236MACRO236*%
%ADD189R,.041X.045*%
%AMMACRO177*
4,1,4,-.00002,.01131,
.01131,.00002,
.00002,-.01131,
-.01131,-.00002,
-.00002,.01131,
0.0*
%
%ADD177MACRO177*%
%AMMACRO102*
4,1,4,-.0085,-.0085,
-.0085,.0085,
.0085,.0085,
.0085,-.0085,
-.0085,-.0085,
0.0*
%
%ADD102MACRO102*%
%AMMACRO99*
4,1,4,-.01202,0.0,
0.0,.01202,
.01202,0.0,
0.0,-.01202,
-.01202,0.0,
0.0*
%
%ADD99MACRO99*%
%AMMACRO59*
4,1,4,0.0,.01202,
.01202,0.0,
0.0,-.01202,
-.01202,0.0,
0.0,.01202,
0.0*
%
%ADD59MACRO59*%
%AMMACRO51*
4,1,4,-.0085,.0085,
.0085,.0085,
.0085,-.0085,
-.0085,-.0085,
-.0085,.0085,
0.0*
%
%ADD51MACRO51*%
%AMMACRO39*
4,1,4,.0085,.0085,
.0085,-.0085,
-.0085,-.0085,
-.0085,.0085,
.0085,.0085,
0.0*
%
%ADD39MACRO39*%
%ADD292R,.013X.039*%
%ADD245R,.063X.024*%
%ADD188R,.063X.06*%
%AMMACRO171*
4,1,4,-.00933,-.00639,
-.00639,.00933,
.00933,.00639,
.00639,-.00933,
-.00933,-.00639,
0.0*
%
%ADD171MACRO171*%
%ADD105R,.018X.07*%
%ADD54R,.063X.061*%
%ADD309R,.032X.039*%
%ADD259R,.039X.013*%
%ADD244R,.071X.035*%
%ADD238R,.064X.024*%
%AMMACRO208*
4,1,44,.0007,-.0102,
.000576,-.010312,
.000434,-.0104,
.000279,-.010462,
.000116,-.010497,
-.000051,-.010503,
-.000216,-.010479,
-.000375,-.010427,
-.000523,-.010349,
-.000654,-.010246,
-.0007,-.0102,
-.0102,-.0007,
-.010312,-.000576,
-.0104,-.000434,
-.010462,-.000279,
-.010497,-.000116,
-.010503,.000051,
-.010479,.000216,
-.010427,.000375,
-.010349,.000523,
-.010246,.000654,
-.0102,.0007,
-.0007,.0102,
-.000576,.010312,
-.000434,.0104,
-.000279,.010462,
-.000116,.010497,
.000051,.010503,
.000216,.010479,
.000375,.010427,
.000523,.010349,
.000654,.010246,
.0007,.0102,
.0102,.0007,
.010312,.000576,
.0104,.000434,
.010462,.000279,
.010497,.000116,
.010503,-.000051,
.010479,-.000216,
.010427,-.000375,
.010349,-.000523,
.010246,-.000654,
.0102,-.0007,
.0007,-.0102,
0.0*
%
%ADD208MACRO208*%
%AMMACRO157*
4,1,4,.00513,.01008,
.01008,-.00513,
-.00513,-.01008,
-.01008,.00513,
.00513,.01008,
0.0*
%
%ADD157MACRO157*%
%AMMACRO138*
4,1,4,.00932,.00641,
.00641,-.00932,
-.00932,-.00641,
-.00641,.00932,
.00932,.00641,
0.0*
%
%ADD138MACRO138*%
%AMMACRO137*
4,1,4,-.00645,-.00929,
-.00929,.00645,
.00645,.00929,
.00929,-.00645,
-.00645,-.00929,
0.0*
%
%ADD137MACRO137*%
%AMMACRO121*
4,1,21,.0055,-.0095,
.005416,-.010455,
.005168,-.011381,
.004763,-.01225,
.004213,-.013035,
.003535,-.013713,
.00275,-.014263,
.001881,-.014668,
.000955,-.014916,
0.0,-.015,
-.000955,-.014916,
-.001881,-.014668,
-.00275,-.014263,
-.003535,-.013713,
-.004213,-.013035,
-.004763,-.01225,
-.005168,-.011381,
-.005416,-.010455,
-.0055,-.0095,
-.0055,.015,
.0055,.015,
.0055,-.0095,
0.0*
%
%ADD121MACRO121*%
%ADD115R,.07X.018*%
%ADD12R,.061X.063*%
%ADD295R,.037X.016*%
%ADD277R,.055X.08*%
%AMMACRO273*
4,1,21,.004,-.013,
-.004,-.013,
-.004,.009,
-.003939,.009695,
-.003759,.010368,
-.003464,.011,
-.003064,.011571,
-.002571,.012064,
-.002,.012464,
-.001368,.012759,
-.000695,.012939,
0.0,.013,
.000695,.012939,
.001368,.012759,
.002,.012464,
.002571,.012064,
.003064,.011571,
.003464,.011,
.003759,.010368,
.003939,.009695,
.004,.009,
.004,-.013,
0.0*
%
%ADD273MACRO273*%
%ADD253R,.02X.079*%
%AMMACRO229*
4,1,40,-.0007,.0099,
-.000566,.010011,
-.000416,.010097,
-.000252,.010155,
-.000081,.010184,
.000092,.010183,
.000263,.010152,
.000426,.010092,
.000575,.010005,
.0007,.0099,
.0099,.0007,
.010011,.000566,
.010097,.000416,
.010155,.000252,
.010184,.000081,
.010183,-.000092,
.010152,-.000263,
.010092,-.000426,
.010005,-.000575,
.0099,-.0007,
.0007,-.0099,
.000566,-.010011,
.000416,-.010097,
.000252,-.010155,
.000081,-.010184,
-.000092,-.010183,
-.000263,-.010152,
-.000426,-.010092,
-.000575,-.010005,
-.0007,-.0099,
-.0099,-.0007,
-.010011,-.000566,
-.010097,-.000416,
-.010155,-.000252,
-.010184,-.000081,
-.010183,.000092,
-.010152,.000263,
-.010092,.000426,
-.010005,.000575,
-.0099,.0007,
-.0007,.0099,
0.0*
%
%ADD229MACRO229*%
%AMMACRO210*
4,1,40,-.0075,.00651,
-.007478,.006683,
-.007432,.00685,
-.007357,.007006,
-.007256,.007147,
-.007132,.007269,
-.006989,.007367,
-.006831,.007439,
-.006663,.007482,
-.00651,.0075,
.00651,.0075,
.006683,.007478,
.00685,.007432,
.007006,.007357,
.007147,.007256,
.007269,.007132,
.007367,.006989,
.007439,.006831,
.007482,.006663,
.0075,.00651,
.0075,-.00651,
.007478,-.006683,
.007432,-.00685,
.007357,-.007006,
.007256,-.007147,
.007132,-.007269,
.006989,-.007367,
.006831,-.007439,
.006663,-.007482,
.00651,-.0075,
-.00651,-.0075,
-.006683,-.007478,
-.00685,-.007432,
-.007006,-.007357,
-.007147,-.007256,
-.007269,-.007132,
-.007367,-.006989,
-.007439,-.006831,
-.007482,-.006663,
-.0075,-.00651,
-.0075,.00651,
0.0*
%
%ADD210MACRO210*%
%AMMACRO203*
4,1,40,.0099,.0007,
.010011,.000566,
.010097,.000416,
.010155,.000252,
.010184,.000081,
.010183,-.000092,
.010152,-.000263,
.010092,-.000426,
.010005,-.000575,
.0099,-.0007,
.0007,-.0099,
.000566,-.010011,
.000416,-.010097,
.000252,-.010155,
.000081,-.010184,
-.000092,-.010183,
-.000263,-.010152,
-.000426,-.010092,
-.000575,-.010005,
-.0007,-.0099,
-.0099,-.0007,
-.010011,-.000566,
-.010097,-.000416,
-.010155,-.000252,
-.010184,-.000081,
-.010183,.000092,
-.010152,.000263,
-.010092,.000426,
-.010005,.000575,
-.0099,.0007,
-.0007,.0099,
-.000566,.010011,
-.000416,.010097,
-.000252,.010155,
-.000081,.010184,
.000092,.010183,
.000263,.010152,
.000426,.010092,
.000575,.010005,
.0007,.0099,
.0099,.0007,
0.0*
%
%ADD203MACRO203*%
%AMMACRO113*
4,1,21,-.006,-.015,
-.006,.009,
-.005909,.010042,
-.005638,.011052,
-.005196,.012,
-.004596,.012857,
-.003857,.013596,
-.003,.014196,
-.002052,.014638,
-.001042,.014909,
0.0,.015,
.001042,.014909,
.002052,.014638,
.003,.014196,
.003857,.013596,
.004596,.012857,
.005196,.012,
.005638,.011052,
.005909,.010042,
.006,.009,
.006,-.015,
-.006,-.015,
0.0*
%
%ADD113MACRO113*%
%ADD103R,.065X.033*%
%AMMACRO220*
4,1,21,-.015,.006,
.009,.006,
.010042,.005909,
.011052,.005638,
.012,.005196,
.012857,.004596,
.013596,.003857,
.014196,.003,
.014638,.002052,
.014909,.001042,
.015,0.0,
.014909,-.001042,
.014638,-.002052,
.014196,-.003,
.013596,-.003857,
.012857,-.004596,
.012,-.005196,
.011052,-.005638,
.010042,-.005909,
.009,-.006,
-.015,-.006,
-.015,.006,
0.0*
%
%ADD220MACRO220*%
%AMMACRO170*
4,1,4,-.00699,-.00889,
-.00889,.00699,
.00699,.00889,
.00889,-.00699,
-.00699,-.00889,
0.0*
%
%ADD170MACRO170*%
%AMMACRO169*
4,1,4,-.00696,-.00891,
-.00891,.00696,
.00696,.00891,
.00891,-.00696,
-.00696,-.00891,
0.0*
%
%ADD169MACRO169*%
%AMMACRO155*
4,1,4,-.0052,-.01004,
-.01004,.0052,
.0052,.01004,
.01004,-.0052,
-.0052,-.01004,
0.0*
%
%ADD155MACRO155*%
%ADD131R,.015X.085*%
%ADD42R,.045X.055*%
%ADD202R,.085X.015*%
%AMMACRO168*
4,1,4,-.00698,-.0089,
-.0089,.00698,
.00698,.0089,
.0089,-.00698,
-.00698,-.0089,
0.0*
%
%ADD168MACRO168*%
%AMMACRO167*
4,1,4,.00698,.0089,
.0089,-.00698,
-.00698,-.0089,
-.0089,.00698,
.00698,.0089,
0.0*
%
%ADD167MACRO167*%
%AMMACRO165*
4,1,4,-.00681,.00903,
.00903,.00681,
.00681,-.00903,
-.00903,-.00681,
-.00681,.00903,
0.0*
%
%ADD165MACRO165*%
%AMMACRO161*
4,1,4,-.00633,.00937,
.00937,.00633,
.00633,-.00937,
-.00937,-.00633,
-.00633,.00937,
0.0*
%
%ADD161MACRO161*%
%ADD129R,.055X.045*%
%ADD101R,.039X.035*%
%AMMACRO98*
21,1,.035,.039,0.0,0.0,45.*%
%ADD98MACRO98*%
%AMMACRO55*
4,1,21,-.01,-.004,
-.010695,-.003939,
-.011368,-.003759,
-.012,-.003464,
-.012571,-.003064,
-.013064,-.002571,
-.013464,-.002,
-.013759,-.001368,
-.013939,-.000695,
-.014,0.0,
-.013939,.000695,
-.013759,.001368,
-.013464,.002,
-.013064,.002571,
-.012571,.003064,
-.012,.003464,
-.011368,.003759,
-.010695,.003939,
-.01,.004,
.014,.004,
.014,-.004,
-.01,-.004,
0.0*
%
%ADD55MACRO55*%
%AMMACRO29*
4,1,21,-.004,.01,
-.003939,.010695,
-.003759,.011368,
-.003464,.012,
-.003064,.012571,
-.002571,.013064,
-.002,.013464,
-.001368,.013759,
-.000695,.013939,
0.0,.014,
.000695,.013939,
.001368,.013759,
.002,.013464,
.002571,.013064,
.003064,.012571,
.003464,.012,
.003759,.011368,
.003939,.010695,
.004,.01,
.004,-.014,
-.004,-.014,
-.004,.01,
0.0*
%
%ADD29MACRO29*%
%ADD185R,.076X.025*%
%AMMACRO173*
4,1,4,.01058,.004,
.004,-.01058,
-.01058,-.004,
-.004,.01058,
.01058,.004,
0.0*
%
%ADD173MACRO173*%
%AMMACRO139*
4,1,4,.00639,.00933,
.00933,-.00639,
-.00639,-.00933,
-.00933,.00639,
.00639,.00933,
0.0*
%
%ADD139MACRO139*%
%ADD97R,.035X.039*%
%ADD45R,.14X.14*%
%ADD302R,.075X.045*%
%ADD260R,.072X.057*%
%ADD249R,.047X.055*%
%AMMACRO225*
4,1,4,-.00801,-.00798,
-.00798,.00801,
.00801,.00798,
.00798,-.00801,
-.00801,-.00798,
0.0*
%
%ADD225MACRO225*%
%AMMACRO190*
4,1,4,-.00245,.01104,
.01104,.00245,
.00245,-.01104,
-.01104,-.00245,
-.00245,.01104,
0.0*
%
%ADD190MACRO190*%
%AMMACRO187*
4,1,4,-.00798,.00801,
.00801,.00798,
.00798,-.00801,
-.00801,-.00798,
-.00798,.00801,
0.0*
%
%ADD187MACRO187*%
%ADD226R,.09X.095*%
%AMMACRO166*
4,1,4,-.00735,.00859,
.00859,.00735,
.00735,-.00859,
-.00859,-.00735,
-.00735,.00859,
0.0*
%
%ADD166MACRO166*%
%AMMACRO158*
4,1,4,-.00355,-.01074,
-.01074,.00355,
.00355,.01074,
.01074,-.00355,
-.00355,-.01074,
0.0*
%
%ADD158MACRO158*%
%AMMACRO119*
4,1,21,-.0055,.0095,
-.005416,.010455,
-.005168,.011381,
-.004763,.01225,
-.004213,.013035,
-.003535,.013713,
-.00275,.014263,
-.001881,.014668,
-.000955,.014916,
0.0,.015,
.000955,.014916,
.001881,.014668,
.00275,.014263,
.003535,.013713,
.004213,.013035,
.004763,.01225,
.005168,.011381,
.005416,.010455,
.0055,.0095,
.0055,-.015,
-.0055,-.015,
-.0055,.0095,
0.0*
%
%ADD119MACRO119*%
%ADD310R,.059X.028*%
%ADD288O,.098X.046*%
%AMMACRO281*
4,1,21,.006,.0225,
.006,-.0165,
.005909,-.017542,
.005638,-.018552,
.005196,-.0195,
.004596,-.020357,
.003857,-.021096,
.003,-.021696,
.002052,-.022138,
.001042,-.022409,
0.0,-.0225,
-.001042,-.022409,
-.002052,-.022138,
-.003,-.021696,
-.003857,-.021096,
-.004596,-.020357,
-.005196,-.0195,
-.005638,-.018552,
-.005909,-.017542,
-.006,-.0165,
-.006,.0225,
.006,.0225,
0.0*
%
%ADD281MACRO281*%
%ADD265R,.095X.09*%
%AMMACRO154*
4,1,4,.00509,.0101,
.0101,-.00509,
-.00509,-.0101,
-.0101,.00509,
.00509,.0101,
0.0*
%
%ADD154MACRO154*%
%AMMACRO112*
4,1,21,.006,.015,
.006,-.009,
.005909,-.010042,
.005638,-.011052,
.005196,-.012,
.004596,-.012857,
.003857,-.013596,
.003,-.014196,
.002052,-.014638,
.001042,-.014909,
0.0,-.015,
-.001042,-.014909,
-.002052,-.014638,
-.003,-.014196,
-.003857,-.013596,
-.004596,-.012857,
-.005196,-.012,
-.005638,-.011052,
-.005909,-.010042,
-.006,-.009,
-.006,.015,
.006,.015,
0.0*
%
%ADD112MACRO112*%
%ADD35R,.079X.071*%
%AMMACRO233*
4,1,21,.015,-.006,
-.009,-.006,
-.010042,-.005909,
-.011052,-.005638,
-.012,-.005196,
-.012857,-.004596,
-.013596,-.003857,
-.014196,-.003,
-.014638,-.002052,
-.014909,-.001042,
-.015,0.0,
-.014909,.001042,
-.014638,.002052,
-.014196,.003,
-.013596,.003857,
-.012857,.004596,
-.012,.005196,
-.011052,.005638,
-.010042,.005909,
-.009,.006,
.015,.006,
.015,-.006,
0.0*
%
%ADD233MACRO233*%
%ADD216R,.071X.079*%
%AMMACRO118*
4,1,21,-.0095,-.0055,
-.010455,-.005416,
-.011381,-.005168,
-.01225,-.004763,
-.013035,-.004213,
-.013713,-.003535,
-.014263,-.00275,
-.014668,-.001881,
-.014916,-.000955,
-.015,0.0,
-.014916,.000955,
-.014668,.001881,
-.014263,.00275,
-.013713,.003535,
-.013035,.004213,
-.01225,.004763,
-.011381,.005168,
-.010455,.005416,
-.0095,.0055,
.015,.0055,
.015,-.0055,
-.0095,-.0055,
0.0*
%
%ADD118MACRO118*%
%AMMACRO174*
4,1,4,-.01062,-.00388,
-.00388,.01062,
.01062,.00388,
.00388,-.01062,
-.01062,-.00388,
0.0*
%
%ADD174MACRO174*%
%AMMACRO153*
4,1,4,.00521,.01004,
.01004,-.00521,
-.00521,-.01004,
-.01004,.00521,
.00521,.01004,
0.0*
%
%ADD153MACRO153*%
%AMMACRO146*
4,1,4,-.00922,-.00655,
-.00655,.00922,
.00922,.00655,
.00655,-.00922,
-.00922,-.00655,
0.0*
%
%ADD146MACRO146*%
%AMMACRO145*
4,1,4,.00922,.00655,
.00655,-.00922,
-.00922,-.00655,
-.00655,.00922,
.00922,.00655,
0.0*
%
%ADD145MACRO145*%
%ADD132R,.063X.089*%
%AMMACRO111*
4,1,21,-.015,.006,
.009,.006,
.010042,.005909,
.011052,.005638,
.012,.005196,
.012857,.004596,
.013596,.003857,
.014196,.003,
.014638,.002052,
.014909,.001042,
.015,0.0,
.014909,-.001042,
.014638,-.002052,
.014196,-.003,
.013596,-.003857,
.012857,-.004596,
.012,-.005196,
.011052,-.005638,
.010042,-.005909,
.009,-.006,
-.015,-.006,
-.015,.006,
0.0*
%
%ADD111MACRO111*%
%AMMACRO221*
4,1,21,.006,.015,
.006,-.009,
.005909,-.010042,
.005638,-.011052,
.005196,-.012,
.004596,-.012857,
.003857,-.013596,
.003,-.014196,
.002052,-.014638,
.001042,-.014909,
0.0,-.015,
-.001042,-.014909,
-.002052,-.014638,
-.003,-.014196,
-.003857,-.013596,
-.004596,-.012857,
-.005196,-.012,
-.005638,-.011052,
-.005909,-.010042,
-.006,-.009,
-.006,.015,
.006,.015,
0.0*
%
%ADD221MACRO221*%
%AMMACRO176*
4,1,4,-.00222,-.01109,
-.01109,.00222,
.00222,.01109,
.01109,-.00222,
-.00222,-.01109,
0.0*
%
%ADD176MACRO176*%
%AMMACRO136*
4,1,4,-.00693,-.00894,
-.00894,.00693,
.00693,.00894,
.00894,-.00693,
-.00693,-.00894,
0.0*
%
%ADD136MACRO136*%
%ADD90R,.089X.063*%
%ADD43R,.079X.092*%
%AMMACRO272*
4,1,21,-.013,-.004,
-.013,.004,
.009,.004,
.009695,.003939,
.010368,.003759,
.011,.003464,
.011571,.003064,
.012064,.002571,
.012464,.002,
.012759,.001368,
.012939,.000695,
.013,0.0,
.012939,-.000695,
.012759,-.001368,
.012464,-.002,
.012064,-.002571,
.011571,-.003064,
.011,-.003464,
.010368,-.003759,
.009695,-.003939,
.009,-.004,
-.013,-.004,
0.0*
%
%ADD272MACRO272*%
%ADD234R,.049X.068*%
%ADD215R,.092X.079*%
%AMMACRO151*
4,1,4,-.0092,-.00658,
-.00658,.0092,
.0092,.00658,
.00658,-.0092,
-.0092,-.00658,
0.0*
%
%ADD151MACRO151*%
%AMMACRO150*
4,1,4,.0093,.00643,
.00643,-.0093,
-.0093,-.00643,
-.00643,.0093,
.0093,.00643,
0.0*
%
%ADD150MACRO150*%
%AMMACRO149*
4,1,4,.00929,.00645,
.00645,-.00929,
-.00929,-.00645,
-.00645,.00929,
.00929,.00645,
0.0*
%
%ADD149MACRO149*%
%AMMACRO141*
4,1,4,-.00929,-.00645,
-.00645,.00929,
.00929,.00645,
.00645,-.00929,
-.00929,-.00645,
0.0*
%
%ADD141MACRO141*%
%AMMACRO282*
4,1,21,-.006,-.0225,
-.006,.0165,
-.005909,.017542,
-.005638,.018552,
-.005196,.0195,
-.004596,.020357,
-.003857,.021096,
-.003,.021696,
-.002052,.022138,
-.001042,.022409,
0.0,.0225,
.001042,.022409,
.002052,.022138,
.003,.021696,
.003857,.021096,
.004596,.020357,
.005196,.0195,
.005638,.018552,
.005909,.017542,
.006,.0165,
.006,-.0225,
-.006,-.0225,
0.0*
%
%ADD282MACRO282*%
%AMMACRO172*
4,1,4,.0043,.01046,
.01046,-.0043,
-.0043,-.01046,
-.01046,.0043,
.0043,.01046,
0.0*
%
%ADD172MACRO172*%
%AMMACRO147*
4,1,4,.00922,.00655,
.00655,-.00922,
-.00922,-.00655,
-.00655,.00922,
.00922,.00655,
0.0*
%
%ADD147MACRO147*%
%AMMACRO143*
4,1,4,.00928,.00647,
.00647,-.00928,
-.00928,-.00647,
-.00647,.00928,
.00928,.00647,
0.0*
%
%ADD143MACRO143*%
%AMMACRO142*
4,1,4,-.00928,-.00647,
-.00647,.00928,
.00928,.00647,
.00647,-.00928,
-.00928,-.00647,
0.0*
%
%ADD142MACRO142*%
%AMMACRO56*
4,1,21,-.004,.01,
-.003939,.010695,
-.003759,.011368,
-.003464,.012,
-.003064,.012571,
-.002571,.013064,
-.002,.013464,
-.001368,.013759,
-.000695,.013939,
0.0,.014,
.000695,.013939,
.001368,.013759,
.002,.013464,
.002571,.013064,
.003064,.012571,
.003464,.012,
.003759,.011368,
.003939,.010695,
.004,.01,
.004,-.014,
-.004,-.014,
-.004,.01,
0.0*
%
%ADD56MACRO56*%
%AMMACRO30*
4,1,21,.01,.004,
.010695,.003939,
.011368,.003759,
.012,.003464,
.012571,.003064,
.013064,.002571,
.013464,.002,
.013759,.001368,
.013939,.000695,
.014,0.0,
.013939,-.000695,
.013759,-.001368,
.013464,-.002,
.013064,-.002571,
.012571,-.003064,
.012,-.003464,
.011368,-.003759,
.010695,-.003939,
.01,-.004,
-.014,-.004,
-.014,.004,
.01,.004,
0.0*
%
%ADD30MACRO30*%
%AMMACRO250*
4,1,4,.00802,.00797,
.00797,-.00802,
-.00802,-.00797,
-.00797,.00802,
.00802,.00797,
0.0*
%
%ADD250MACRO250*%
%AMMACRO179*
4,1,4,-.00002,-.01131,
-.01131,.00002,
.00002,.01131,
.01131,-.00002,
-.00002,-.01131,
0.0*
%
%ADD179MACRO179*%
%AMMACRO148*
4,1,4,.00927,.00648,
.00648,-.00927,
-.00927,-.00648,
-.00648,.00927,
.00927,.00648,
0.0*
%
%ADD148MACRO148*%
%AMMACRO144*
4,1,4,-.00927,-.00648,
-.00648,.00927,
.00927,.00648,
.00648,-.00927,
-.00927,-.00648,
0.0*
%
%ADD144MACRO144*%
%AMMACRO140*
4,1,4,.00921,.00657,
.00657,-.00921,
-.00921,-.00657,
-.00657,.00921,
.00921,.00657,
0.0*
%
%ADD140MACRO140*%
%AMMACRO279*
4,1,21,.0225,-.006,
-.0165,-.006,
-.017542,-.005909,
-.018552,-.005638,
-.0195,-.005196,
-.020357,-.004596,
-.021096,-.003857,
-.021696,-.003,
-.022138,-.002052,
-.022409,-.001042,
-.0225,0.0,
-.022409,.001042,
-.022138,.002052,
-.021696,.003,
-.021096,.003857,
-.020357,.004596,
-.0195,.005196,
-.018552,.005638,
-.017542,.005909,
-.0165,.006,
.0225,.006,
.0225,-.006,
0.0*
%
%ADD279MACRO279*%
%AMMACRO152*
4,1,4,.00426,.01048,
.01048,-.00426,
-.00426,-.01048,
-.01048,.00426,
.00426,.01048,
0.0*
%
%ADD152MACRO152*%
%AMMACRO123*
4,1,40,-.007,-.011,
.007,-.011,
.007695,-.010939,
.008368,-.010759,
.009,-.010464,
.009571,-.010064,
.010064,-.009571,
.010464,-.009,
.010759,-.008368,
.010939,-.007695,
.011,-.007,
.011,.007,
.010939,.007695,
.010759,.008368,
.010464,.009,
.010064,.009571,
.009571,.010064,
.009,.010464,
.008368,.010759,
.007695,.010939,
.007,.011,
-.007,.011,
-.007695,.010939,
-.008368,.010759,
-.009,.010464,
-.009571,.010064,
-.010064,.009571,
-.010464,.009,
-.010759,.008368,
-.010939,.007695,
-.011,.007,
-.011,-.007,
-.010939,-.007695,
-.010759,-.008368,
-.010464,-.009,
-.010064,-.009571,
-.009571,-.010064,
-.009,-.010464,
-.008368,-.010759,
-.007695,-.010939,
-.007,-.011,
0.0*
%
%ADD123MACRO123*%
%AMMACRO76*
4,1,40,-.008,-.012,
.008,-.012,
.008695,-.011939,
.009368,-.011759,
.01,-.011464,
.010571,-.011064,
.011064,-.010571,
.011464,-.01,
.011759,-.009368,
.011939,-.008695,
.012,-.008,
.012,.008,
.011939,.008695,
.011759,.009368,
.011464,.01,
.011064,.010571,
.010571,.011064,
.01,.011464,
.009368,.011759,
.008695,.011939,
.008,.012,
-.008,.012,
-.008695,.011939,
-.009368,.011759,
-.01,.011464,
-.010571,.011064,
-.011064,.010571,
-.011464,.01,
-.011759,.009368,
-.011939,.008695,
-.012,.008,
-.012,-.008,
-.011939,-.008695,
-.011759,-.009368,
-.011464,-.01,
-.011064,-.010571,
-.010571,-.011064,
-.01,-.011464,
-.009368,-.011759,
-.008695,-.011939,
-.008,-.012,
0.0*
%
%ADD76MACRO76*%
%AMMACRO25*
4,1,40,.012,-.008,
.012,.008,
.011939,.008695,
.011759,.009368,
.011464,.01,
.011064,.010571,
.010571,.011064,
.01,.011464,
.009368,.011759,
.008695,.011939,
.008,.012,
-.008,.012,
-.008695,.011939,
-.009368,.011759,
-.01,.011464,
-.010571,.011064,
-.011064,.010571,
-.011464,.01,
-.011759,.009368,
-.011939,.008695,
-.012,.008,
-.012,-.008,
-.011939,-.008695,
-.011759,-.009368,
-.011464,-.01,
-.011064,-.010571,
-.010571,-.011064,
-.01,-.011464,
-.009368,-.011759,
-.008695,-.011939,
-.008,-.012,
.008,-.012,
.008695,-.011939,
.009368,-.011759,
.01,-.011464,
.010571,-.011064,
.011064,-.010571,
.011464,-.01,
.011759,-.009368,
.011939,-.008695,
.012,-.008,
0.0*
%
%ADD25MACRO25*%
%AMMACRO52*
4,1,40,-.011,.007,
-.011,-.007,
-.010939,-.007695,
-.010759,-.008368,
-.010464,-.009,
-.010064,-.009571,
-.009571,-.010064,
-.009,-.010464,
-.008368,-.010759,
-.007695,-.010939,
-.007,-.011,
.007,-.011,
.007695,-.010939,
.008368,-.010759,
.009,-.010464,
.009571,-.010064,
.010064,-.009571,
.010464,-.009,
.010759,-.008368,
.010939,-.007695,
.011,-.007,
.011,.007,
.010939,.007695,
.010759,.008368,
.010464,.009,
.010064,.009571,
.009571,.010064,
.009,.010464,
.008368,.010759,
.007695,.010939,
.007,.011,
-.007,.011,
-.007695,.010939,
-.008368,.010759,
-.009,.010464,
-.009571,.010064,
-.010064,.009571,
-.010464,.009,
-.010759,.008368,
-.010939,.007695,
-.011,.007,
0.0*
%
%ADD52MACRO52*%
%AMMACRO271*
4,1,21,.013,.004,
.013,-.004,
-.009,-.004,
-.009695,-.003939,
-.010368,-.003759,
-.011,-.003464,
-.011571,-.003064,
-.012064,-.002571,
-.012464,-.002,
-.012759,-.001368,
-.012939,-.000695,
-.013,0.0,
-.012939,.000695,
-.012759,.001368,
-.012464,.002,
-.012064,.002571,
-.011571,.003064,
-.011,.003464,
-.010368,.003759,
-.009695,.003939,
-.009,.004,
.013,.004,
0.0*
%
%ADD271MACRO271*%
%AMMACRO199*
4,1,40,.017,-.013,
.017,.013,
.016939,.013695,
.016759,.014368,
.016464,.015,
.016064,.015571,
.015571,.016064,
.015,.016464,
.014368,.016759,
.013695,.016939,
.013,.017,
-.013,.017,
-.013695,.016939,
-.014368,.016759,
-.015,.016464,
-.015571,.016064,
-.016064,.015571,
-.016464,.015,
-.016759,.014368,
-.016939,.013695,
-.017,.013,
-.017,-.013,
-.016939,-.013695,
-.016759,-.014368,
-.016464,-.015,
-.016064,-.015571,
-.015571,-.016064,
-.015,-.016464,
-.014368,-.016759,
-.013695,-.016939,
-.013,-.017,
.013,-.017,
.013695,-.016939,
.014368,-.016759,
.015,-.016464,
.015571,-.016064,
.016064,-.015571,
.016464,-.015,
.016759,-.014368,
.016939,-.013695,
.017,-.013,
0.0*
%
%ADD199MACRO199*%
%AMMACRO191*
4,1,4,.00295,.01092,
.01092,-.00295,
-.00295,-.01092,
-.01092,.00295,
.00295,.01092,
0.0*
%
%ADD191MACRO191*%
%AMMACRO27*
4,1,40,.013,.017,
-.013,.017,
-.013695,.016939,
-.014368,.016759,
-.015,.016464,
-.015571,.016064,
-.016064,.015571,
-.016464,.015,
-.016759,.014368,
-.016939,.013695,
-.017,.013,
-.017,-.013,
-.016939,-.013695,
-.016759,-.014368,
-.016464,-.015,
-.016064,-.015571,
-.015571,-.016064,
-.015,-.016464,
-.014368,-.016759,
-.013695,-.016939,
-.013,-.017,
.013,-.017,
.013695,-.016939,
.014368,-.016759,
.015,-.016464,
.015571,-.016064,
.016064,-.015571,
.016464,-.015,
.016759,-.014368,
.016939,-.013695,
.017,-.013,
.017,.013,
.016939,.013695,
.016759,.014368,
.016464,.015,
.016064,.015571,
.015571,.016064,
.015,.016464,
.014368,.016759,
.013695,.016939,
.013,.017,
0.0*
%
%ADD27MACRO27*%
%AMMACRO270*
4,1,21,-.004,.013,
.004,.013,
.004,-.009,
.003939,-.009695,
.003759,-.010368,
.003464,-.011,
.003064,-.011571,
.002571,-.012064,
.002,-.012464,
.001368,-.012759,
.000695,-.012939,
0.0,-.013,
-.000695,-.012939,
-.001368,-.012759,
-.002,-.012464,
-.002571,-.012064,
-.003064,-.011571,
-.003464,-.011,
-.003759,-.010368,
-.003939,-.009695,
-.004,-.009,
-.004,.013,
0.0*
%
%ADD270MACRO270*%
%AMMACRO61*
4,1,21,-.01,-.004,
-.010695,-.003939,
-.011368,-.003759,
-.012,-.003464,
-.012571,-.003064,
-.013064,-.002571,
-.013464,-.002,
-.013759,-.001368,
-.013939,-.000695,
-.014,0.0,
-.013939,.000695,
-.013759,.001368,
-.013464,.002,
-.013064,.002571,
-.012571,.003064,
-.012,.003464,
-.011368,.003759,
-.010695,.003939,
-.01,.004,
.014,.004,
.014,-.004,
-.01,-.004,
0.0*
%
%ADD61MACRO61*%
%AMMACRO58*
4,1,21,.004,-.01,
.003939,-.010695,
.003759,-.011368,
.003464,-.012,
.003064,-.012571,
.002571,-.013064,
.002,-.013464,
.001368,-.013759,
.000695,-.013939,
0.0,-.014,
-.000695,-.013939,
-.001368,-.013759,
-.002,-.013464,
-.002571,-.013064,
-.003064,-.012571,
-.003464,-.012,
-.003759,-.011368,
-.003939,-.010695,
-.004,-.01,
-.004,.014,
.004,.014,
.004,-.01,
0.0*
%
%ADD58MACRO58*%
%AMMACRO57*
4,1,21,.01,.004,
.010695,.003939,
.011368,.003759,
.012,.003464,
.012571,.003064,
.013064,.002571,
.013464,.002,
.013759,.001368,
.013939,.000695,
.014,0.0,
.013939,-.000695,
.013759,-.001368,
.013464,-.002,
.013064,-.002571,
.012571,-.003064,
.012,-.003464,
.011368,-.003759,
.010695,-.003939,
.01,-.004,
-.014,-.004,
-.014,.004,
.01,.004,
0.0*
%
%ADD57MACRO57*%
%AMMACRO31*
4,1,21,.004,-.01,
.003939,-.010695,
.003759,-.011368,
.003464,-.012,
.003064,-.012571,
.002571,-.013064,
.002,-.013464,
.001368,-.013759,
.000695,-.013939,
0.0,-.014,
-.000695,-.013939,
-.001368,-.013759,
-.002,-.013464,
-.002571,-.013064,
-.003064,-.012571,
-.003464,-.012,
-.003759,-.011368,
-.003939,-.010695,
-.004,-.01,
-.004,.014,
.004,.014,
.004,-.01,
0.0*
%
%ADD31MACRO31*%
%AMMACRO299*
4,1,4,-.01131,.00003,
.00003,.01131,
.01131,-.00003,
-.00003,-.01131,
-.01131,.00003,
0.0*
%
%ADD299MACRO299*%
%AMMACRO231*
4,1,4,.00003,.01131,
.01131,-.00003,
-.00003,-.01131,
-.01131,.00003,
.00003,.01131,
0.0*
%
%ADD231MACRO231*%
%AMMACRO192*
4,1,4,-.00295,-.01092,
-.01092,.00295,
.00295,.01092,
.01092,-.00295,
-.00295,-.01092,
0.0*
%
%ADD192MACRO192*%
%AMMACRO248*
4,1,4,-.00006,-.01131,
-.01131,.00006,
.00006,.01131,
.01131,-.00006,
-.00006,-.01131,
0.0*
%
%ADD248MACRO248*%
%AMMACRO124*
4,1,40,-.007,-.011,
.007,-.011,
.007695,-.010939,
.008368,-.010759,
.009,-.010464,
.009571,-.010064,
.010064,-.009571,
.010464,-.009,
.010759,-.008368,
.010939,-.007695,
.011,-.007,
.011,.007,
.010939,.007695,
.010759,.008368,
.010464,.009,
.010064,.009571,
.009571,.010064,
.009,.010464,
.008368,.010759,
.007695,.010939,
.007,.011,
-.007,.011,
-.007695,.010939,
-.008368,.010759,
-.009,.010464,
-.009571,.010064,
-.010064,.009571,
-.010464,.009,
-.010759,.008368,
-.010939,.007695,
-.011,.007,
-.011,-.007,
-.010939,-.007695,
-.010759,-.008368,
-.010464,-.009,
-.010064,-.009571,
-.009571,-.010064,
-.009,-.010464,
-.008368,-.010759,
-.007695,-.010939,
-.007,-.011,
0.0*
%
%ADD124MACRO124*%
%AMMACRO77*
4,1,40,-.008,-.012,
.008,-.012,
.008695,-.011939,
.009368,-.011759,
.01,-.011464,
.010571,-.011064,
.011064,-.010571,
.011464,-.01,
.011759,-.009368,
.011939,-.008695,
.012,-.008,
.012,.008,
.011939,.008695,
.011759,.009368,
.011464,.01,
.011064,.010571,
.010571,.011064,
.01,.011464,
.009368,.011759,
.008695,.011939,
.008,.012,
-.008,.012,
-.008695,.011939,
-.009368,.011759,
-.01,.011464,
-.010571,.011064,
-.011064,.010571,
-.011464,.01,
-.011759,.009368,
-.011939,.008695,
-.012,.008,
-.012,-.008,
-.011939,-.008695,
-.011759,-.009368,
-.011464,-.01,
-.011064,-.010571,
-.010571,-.011064,
-.01,-.011464,
-.009368,-.011759,
-.008695,-.011939,
-.008,-.012,
0.0*
%
%ADD77MACRO77*%
%AMMACRO26*
4,1,40,.012,-.008,
.012,.008,
.011939,.008695,
.011759,.009368,
.011464,.01,
.011064,.010571,
.010571,.011064,
.01,.011464,
.009368,.011759,
.008695,.011939,
.008,.012,
-.008,.012,
-.008695,.011939,
-.009368,.011759,
-.01,.011464,
-.010571,.011064,
-.011064,.010571,
-.011464,.01,
-.011759,.009368,
-.011939,.008695,
-.012,.008,
-.012,-.008,
-.011939,-.008695,
-.011759,-.009368,
-.011464,-.01,
-.011064,-.010571,
-.010571,-.011064,
-.01,-.011464,
-.009368,-.011759,
-.008695,-.011939,
-.008,-.012,
.008,-.012,
.008695,-.011939,
.009368,-.011759,
.01,-.011464,
.010571,-.011064,
.011064,-.010571,
.011464,-.01,
.011759,-.009368,
.011939,-.008695,
.012,-.008,
0.0*
%
%ADD26MACRO26*%
%AMMACRO53*
4,1,40,-.011,.007,
-.011,-.007,
-.010939,-.007695,
-.010759,-.008368,
-.010464,-.009,
-.010064,-.009571,
-.009571,-.010064,
-.009,-.010464,
-.008368,-.010759,
-.007695,-.010939,
-.007,-.011,
.007,-.011,
.007695,-.010939,
.008368,-.010759,
.009,-.010464,
.009571,-.010064,
.010064,-.009571,
.010464,-.009,
.010759,-.008368,
.010939,-.007695,
.011,-.007,
.011,.007,
.010939,.007695,
.010759,.008368,
.010464,.009,
.010064,.009571,
.009571,.010064,
.009,.010464,
.008368,.010759,
.007695,.010939,
.007,.011,
-.007,.011,
-.007695,.010939,
-.008368,.010759,
-.009,.010464,
-.009571,.010064,
-.010064,.009571,
-.010464,.009,
-.010759,.008368,
-.010939,.007695,
-.011,.007,
0.0*
%
%ADD53MACRO53*%
%ADD313C,.02*%
%ADD314C,.006*%
%ADD315C,.177*%
G75*
%LPD*%
G75*
G36*
G01X78000Y304500D02*
X65000D01*
Y291500D01*
X78000D01*
Y304500D01*
G37*
G36*
G01X654719Y306448D02*
X679319D01*
Y331048D01*
X654719D01*
Y306448D01*
G37*
G36*
G01X1528921Y23968D02*
G03I-2050J0D01*
G37*
G36*
G01X1539950Y262450D02*
Y270550D01*
X1542500D01*
Y274900D01*
X1543250D01*
Y272000D01*
X1544750D01*
Y274900D01*
X1545500D01*
Y270550D01*
X1548050D01*
Y262450D01*
X1545500D01*
Y258100D01*
X1544750D01*
Y261000D01*
X1543250D01*
Y258100D01*
X1542500D01*
Y262450D01*
X1539950D01*
G37*
G36*
G01X1628453Y347196D02*
X1636553D01*
Y339096D01*
X1628453D01*
Y347196D01*
G37*
G36*
G01X1626869Y302692D02*
G03I-13800J0D01*
G37*
G36*
G01X1715996Y491260D02*
Y500260D01*
X1706096D01*
Y498960D01*
X1709196D01*
Y497693D01*
X1706096D01*
Y496393D01*
X1709196D01*
Y495127D01*
X1706096D01*
Y493827D01*
X1709196D01*
Y492560D01*
X1706096D01*
Y491260D01*
X1715996D01*
G37*
G36*
G01X1883645Y23968D02*
G03I-2050J0D01*
G37*
G36*
G01X1935009Y84406D02*
X1944009D01*
Y94306D01*
X1942709D01*
Y91206D01*
X1941442D01*
Y94306D01*
X1940142D01*
Y91206D01*
X1938876D01*
Y94306D01*
X1937576D01*
Y91206D01*
X1936309D01*
Y94306D01*
X1935009D01*
Y84406D01*
G37*
%LPC*%
G75*
G54D315*
X1613069Y302692D03*
%LPD*%
G75*
G36*
G01X46750Y6275D02*
Y-8225D01*
X32250D01*
Y6275D01*
X46750D01*
G37*
G36*
G01X850Y511050D02*
X15350D01*
Y496550D01*
X850D01*
Y511050D01*
G37*
G36*
G01X69400Y356900D02*
Y371100D01*
X83600D01*
Y356900D01*
X69400D01*
G37*
G36*
G01X658850Y270250D02*
X673350D01*
Y255750D01*
X658850D01*
Y270250D01*
G37*
G36*
G01X715900Y8300D02*
X726100D01*
Y1700D01*
X715900D01*
Y8300D01*
G37*
G36*
G01X674348Y21537D02*
Y11337D01*
X667748D01*
Y21537D01*
X674348D01*
G37*
G36*
G01X708150Y43850D02*
X700250D01*
Y49750D01*
X708150D01*
Y43850D01*
G37*
G36*
G01X698750D02*
X690850D01*
Y49750D01*
X698750D01*
Y43850D01*
G37*
G36*
G01X708150Y51750D02*
X690850D01*
Y61150D01*
X708150D01*
Y51750D01*
G37*
G36*
G01X718400Y267900D02*
Y282100D01*
X732600D01*
Y267900D01*
X718400D01*
G37*
G36*
G01X725143Y586402D02*
X714943D01*
Y593002D01*
X725143D01*
Y586402D01*
G37*
G36*
G01X674747Y585530D02*
Y575330D01*
X668147D01*
Y585530D01*
X674747D01*
G37*
G36*
G01X708150Y530100D02*
X700250D01*
Y536000D01*
X708150D01*
Y530100D01*
G37*
G36*
G01X698750D02*
X690850D01*
Y536000D01*
X698750D01*
Y530100D01*
G37*
G36*
G01X708150Y538000D02*
X690850D01*
Y547400D01*
X708150D01*
Y538000D01*
G37*
G36*
G01X1349750Y67750D02*
X1364250D01*
Y53250D01*
X1349750D01*
Y67750D01*
G37*
G36*
G01X1368350Y103800D02*
X1360450D01*
Y109700D01*
X1368350D01*
Y103800D01*
G37*
G36*
G01X1358950D02*
X1351050D01*
Y109700D01*
X1358950D01*
Y103800D01*
G37*
G36*
G01X1368350Y111700D02*
X1351050D01*
Y121100D01*
X1368350D01*
Y111700D01*
G37*
G36*
G01X1363150Y514400D02*
X1355250D01*
Y520300D01*
X1363150D01*
Y514400D01*
G37*
G36*
G01X1353750D02*
X1345850D01*
Y520300D01*
X1353750D01*
Y514400D01*
G37*
G36*
G01X1363150Y522300D02*
X1345850D01*
Y531700D01*
X1363150D01*
Y522300D01*
G37*
G36*
G01X1421810Y536705D02*
X1407310D01*
Y551205D01*
X1421810D01*
Y536705D01*
G37*
G36*
G01X1585900Y-4200D02*
Y3000D01*
X1593100D01*
Y-4200D01*
X1585900D01*
G37*
G36*
G01X1590741Y584748D02*
X1580541D01*
Y591348D01*
X1590741D01*
Y584748D01*
G37*
G36*
G01X1565450Y598250D02*
X1550950D01*
Y612750D01*
X1565450D01*
Y598250D01*
G37*
G36*
G01X1708428Y514650D02*
X1714728D01*
Y511150D01*
X1708428D01*
Y514650D01*
G37*
G36*
G01X1733743Y598342D02*
Y591142D01*
X1726543D01*
Y598342D01*
X1733743D01*
G37*
G36*
G01X1784900Y83900D02*
Y94100D01*
X1791500D01*
Y83900D01*
X1784900D01*
G37*
G36*
G01X1815200Y154400D02*
Y164600D01*
X1821800D01*
Y154400D01*
X1815200D01*
G37*
G36*
G01X1840500Y89000D02*
Y92500D01*
X1844000D01*
Y89000D01*
X1840500D01*
G37*
G36*
G01X1889550Y113450D02*
X1873450D01*
Y129550D01*
X1889550D01*
Y113450D01*
G37*
G36*
G01X1855800Y152700D02*
X1845600D01*
Y159300D01*
X1855800D01*
Y152700D01*
G37*
G36*
G01X1957726Y98446D02*
Y104746D01*
X1961226D01*
Y98446D01*
X1957726D01*
G37*
G36*
G01X1913600Y180200D02*
Y166000D01*
X1899400D01*
Y180200D01*
X1913600D01*
G37*
G54D100*
X388187Y-5822D03*
Y31978D03*
Y69778D03*
Y532955D03*
Y570755D03*
Y608555D03*
X1037797Y-5822D03*
Y31978D03*
Y69778D03*
Y570755D03*
Y532955D03*
Y608555D03*
G54D101*
X380892Y91500D03*
Y97000D03*
Y505756D03*
Y511256D03*
X642823Y131000D03*
Y136500D03*
X647561Y131000D03*
Y136500D03*
X1030500Y91500D03*
Y97000D03*
Y505756D03*
Y511256D03*
G54D200*
X1510127Y79413D03*
Y160909D03*
G54D110*
X652700Y275600D03*
X693962Y313316D03*
X689000Y312366D03*
G54D111*
X649819Y303981D03*
Y305950D03*
Y307919D03*
Y309888D03*
Y311857D03*
Y313826D03*
Y315795D03*
Y317764D03*
Y319733D03*
Y321702D03*
Y323671D03*
Y325640D03*
Y327609D03*
Y329578D03*
Y331547D03*
Y333516D03*
G54D210*
X1484094Y484469D03*
G54D102*
X398408Y106083D03*
X410543Y112617D03*
X396832Y114253D03*
X389148Y112345D03*
X404022Y112970D03*
X424817Y111219D03*
X433172Y108790D03*
X439767Y105158D03*
X481792Y112900D03*
X488242Y116350D03*
X697307Y275728D03*
X1048016Y106083D03*
X1060718Y112050D03*
X1074425Y111219D03*
X1045884Y114809D03*
X1081142Y110428D03*
X1090500Y104033D03*
X1038756Y112345D03*
X1053630Y112970D03*
X1131400Y112900D03*
X1118586Y143516D03*
X1138850Y115350D03*
X1134363Y143064D03*
X1141231Y139841D03*
G54D300*
X1953940Y219803D03*
Y221771D03*
Y229645D03*
Y227677D03*
G54D201*
X1507076Y93586D03*
Y91618D03*
Y89649D03*
Y87681D03*
Y85712D03*
Y83744D03*
Y154610D03*
Y152641D03*
Y150673D03*
Y148704D03*
Y138862D03*
Y136893D03*
Y134925D03*
Y132956D03*
Y130988D03*
Y129019D03*
Y127051D03*
Y125082D03*
Y123114D03*
Y121145D03*
Y119177D03*
Y117208D03*
Y115240D03*
Y113271D03*
Y111303D03*
Y109334D03*
Y107366D03*
Y105397D03*
Y103429D03*
Y101460D03*
Y99492D03*
Y97523D03*
Y95555D03*
Y156578D03*
X1536801Y94570D03*
Y92602D03*
Y90633D03*
Y88665D03*
Y86696D03*
Y84728D03*
Y155594D03*
Y153626D03*
Y151657D03*
Y149689D03*
Y139846D03*
Y137878D03*
Y135909D03*
Y133941D03*
Y131972D03*
Y130004D03*
Y128035D03*
Y126067D03*
Y124098D03*
Y122130D03*
Y120161D03*
Y118192D03*
Y116224D03*
Y114255D03*
Y112287D03*
Y110318D03*
Y108350D03*
Y106381D03*
Y104413D03*
Y102444D03*
Y100476D03*
Y98507D03*
Y96539D03*
G54D120*
X688350Y61358D03*
Y59390D03*
Y57421D03*
Y55453D03*
Y53484D03*
Y51516D03*
Y49547D03*
Y47579D03*
Y45610D03*
Y43642D03*
Y547608D03*
Y545640D03*
Y543671D03*
Y541703D03*
Y539734D03*
Y537766D03*
Y535797D03*
Y533829D03*
Y531860D03*
Y529892D03*
X1348550Y121308D03*
Y119340D03*
Y117371D03*
Y115403D03*
Y113434D03*
Y111466D03*
Y109497D03*
Y107529D03*
Y105560D03*
Y103592D03*
X1343350Y526003D03*
Y524034D03*
Y522066D03*
Y520097D03*
Y518129D03*
Y516160D03*
Y514192D03*
Y531908D03*
Y529940D03*
Y527971D03*
G54D112*
X652252Y335948D03*
X654221D03*
X656190D03*
X658159D03*
X660128D03*
X662097D03*
X664066D03*
X666035D03*
X668004D03*
X669973D03*
X671942D03*
X673911D03*
X675880D03*
X677849D03*
X679818D03*
X681787D03*
G54D310*
X1962401Y483109D03*
Y494924D03*
Y500829D03*
G54D202*
X1520972Y300937D03*
Y293257D03*
Y308617D03*
Y295817D03*
Y298377D03*
Y303497D03*
Y306057D03*
X1544472Y308617D03*
Y300937D03*
Y293257D03*
Y295817D03*
Y298377D03*
Y303497D03*
Y306057D03*
X1773471Y564015D03*
X1749971Y556335D03*
Y564015D03*
Y571695D03*
X1773471D03*
Y556335D03*
Y569135D03*
Y566575D03*
Y561455D03*
Y558895D03*
X1749971Y569135D03*
Y566575D03*
Y561455D03*
Y558895D03*
X1748800Y581750D03*
X1772300D03*
Y586870D03*
Y584310D03*
X1748800Y586870D03*
Y584310D03*
X1772300Y589430D03*
X1748800D03*
Y597110D03*
X1772300D03*
Y594550D03*
Y591990D03*
X1748800Y594550D03*
Y591990D03*
G54D220*
X1583398Y-4537D03*
Y-2569D03*
Y-600D03*
Y1369D03*
Y3337D03*
G54D103*
X600150Y122700D03*
Y117700D03*
Y112700D03*
X589650Y117700D03*
Y112700D03*
Y122700D03*
X1241406Y119155D03*
Y114155D03*
Y109155D03*
X1230906Y114155D03*
Y109155D03*
Y119155D03*
G54D121*
X708358Y63650D03*
X706390D03*
X704421D03*
X702453D03*
X700484D03*
X698516D03*
X696547D03*
X694579D03*
X692610D03*
X690642D03*
X708358Y549900D03*
X706390D03*
X704421D03*
X702453D03*
X700484D03*
X698516D03*
X696547D03*
X694579D03*
X692610D03*
X690642D03*
X1368558Y123600D03*
X1366590D03*
X1364621D03*
X1362653D03*
X1360684D03*
X1358716D03*
X1356747D03*
X1354779D03*
X1352810D03*
X1350842D03*
X1363358Y534200D03*
X1361390D03*
X1359421D03*
X1357453D03*
X1355484D03*
X1353516D03*
X1351547D03*
X1349579D03*
X1347610D03*
X1345642D03*
G54D211*
X1481800Y582200D03*
Y553700D03*
G54D130*
X684219Y333516D03*
Y331547D03*
Y329578D03*
Y327609D03*
Y325640D03*
Y323671D03*
Y321702D03*
Y319733D03*
Y317764D03*
Y315795D03*
Y313826D03*
Y311857D03*
Y309888D03*
Y307919D03*
Y305950D03*
Y303981D03*
G54D301*
X1953740Y235551D03*
G36*
G01X25Y18150D02*
G02X0Y-18150I-25J-18150D01*
G02X-25Y18150I0J18150D01*
G01Y11200D01*
G03X0Y-11200I25J-11200D01*
G03X25Y11200I0J11200D01*
G01Y18150D01*
G37*
G54D140*
X1252354Y276226D03*
G54D221*
X1586547Y5502D03*
X1592453D03*
G54D302*
X1918885Y224779D03*
Y235941D03*
G54D131*
X687527Y379176D03*
X679847Y402676D03*
X687527D03*
X695207D03*
Y379176D03*
X679847D03*
X692647D03*
X690087D03*
X684967D03*
X682407D03*
X692647Y402676D03*
X690087D03*
X684967D03*
X682407D03*
G54D113*
X662097Y301548D03*
X660128D03*
X658159D03*
X656190D03*
X654221D03*
X652252D03*
X681787D03*
X679818D03*
X677849D03*
X675880D03*
X673911D03*
X671942D03*
X669973D03*
X668004D03*
X666035D03*
X664066D03*
G54D203*
X1496004Y374823D03*
X1499941D03*
X1503878D03*
X1507815D03*
X1511752D03*
X1515689D03*
X1519626Y368287D03*
Y374823D03*
Y371555D03*
X1523563Y374823D03*
X1527500D03*
X1488130D03*
X1492067D03*
X1494035Y369921D03*
Y373189D03*
X1490098D03*
X1486161D03*
X1492067Y371555D03*
Y368287D03*
X1488130Y371555D03*
X1490098Y369921D03*
X1525531Y373189D03*
X1523563Y371555D03*
X1521594Y369921D03*
X1525531D03*
X1527500Y371555D03*
Y368287D03*
X1521594Y373189D03*
X1523563Y368287D03*
X1499941Y371555D03*
X1511752Y368287D03*
X1509783Y369921D03*
X1497972D03*
Y373189D03*
X1507815Y368287D03*
X1505846Y369921D03*
X1496004Y368287D03*
X1503878D03*
X1517657Y373189D03*
Y369921D03*
X1505846Y373189D03*
X1507815Y371555D03*
X1503878D03*
X1515689D03*
Y368287D03*
X1501909Y369921D03*
X1513720Y373189D03*
X1511752Y371555D03*
X1501909Y373189D03*
X1499941Y368287D03*
X1513720Y369921D03*
X1509783Y373189D03*
X1496004Y371555D03*
X1527500Y496713D03*
X1511752D03*
X1507815D03*
X1519626D03*
X1523563D03*
X1492067D03*
X1496004D03*
X1499941D03*
X1503878D03*
X1515689D03*
X1562933Y374823D03*
X1566870D03*
X1558996Y368287D03*
Y374823D03*
Y371555D03*
X1531437Y374823D03*
X1533406Y369921D03*
Y373189D03*
X1535374Y374823D03*
X1539311D03*
X1543248D03*
X1547185D03*
X1551122D03*
X1555059D03*
X1529469Y369921D03*
X1531437Y371555D03*
Y368287D03*
X1529469Y373189D03*
X1566870Y371555D03*
X1564902Y373189D03*
Y369921D03*
X1562933Y371555D03*
X1560965Y369921D03*
X1568839Y373189D03*
X1560965D03*
X1562933Y368287D03*
X1553091Y369921D03*
X1535374Y371555D03*
X1539311Y368287D03*
X1541280Y369921D03*
X1543248Y371555D03*
X1537343Y369921D03*
X1535374Y368287D03*
X1539311Y371555D03*
X1557028Y373189D03*
Y369921D03*
X1545217D03*
X1555059Y371555D03*
X1541280Y373189D03*
X1551122Y371555D03*
X1549154Y373189D03*
X1553091D03*
X1555059Y368287D03*
X1547185Y371555D03*
X1549154Y369921D03*
X1543248Y368287D03*
X1547185D03*
X1551122D03*
X1545217Y373189D03*
X1537343D03*
X1562933Y496713D03*
X1535374D03*
X1547185D03*
X1543248D03*
X1539311D03*
X1531437D03*
X1551122D03*
X1555059D03*
X1558996D03*
G54D230*
X1557500Y350500D03*
X1552400D03*
X1547300Y350658D03*
X1874600Y140762D03*
G54D311*
X1970071Y540467D03*
X1963071D03*
X1970071Y545979D03*
X1963071D03*
G54D212*
X1481828Y599224D03*
X1517366Y600492D03*
G54D104*
X570000Y473000D03*
X598000D03*
X576900Y499100D03*
X604900D03*
X656800Y82000D03*
X654900Y103050D03*
X643500Y188500D03*
X649500Y239900D03*
X659000Y472700D03*
X684800Y82000D03*
X716500Y129500D03*
X672500Y129000D03*
X700500D03*
X682900Y103050D03*
X689000Y188300D03*
X717000D03*
X671500Y188500D03*
X677500Y239900D03*
X687000Y472700D03*
X744500Y129500D03*
X1224850Y500200D03*
X1252850D03*
X1337100Y554900D03*
X1309100D03*
X1568400Y552200D03*
X1540400D03*
X1800000Y505900D03*
X1828000D03*
G54D122*
X699300Y36012D03*
X1357000Y96213D03*
X1620827Y95153D03*
X1624188Y96700D03*
X1634977Y96860D03*
X1615749Y96720D03*
X1590991Y202378D03*
X1658500Y179742D03*
G54D20*
X16117Y-43892D03*
X38500Y613000D03*
X8543Y636173D03*
X136670Y159840D03*
X166595Y431153D03*
X572500Y105000D03*
X719000Y331200D03*
X796000Y103000D03*
X827000Y181000D03*
X828000Y417500D03*
X1440000Y513000D03*
X1567200Y88000D03*
X1573000Y576900D03*
X1684907Y203562D03*
X1926693Y646063D03*
G54D11*
X-16420Y27510D03*
X-16320Y42550D03*
X-6380Y27510D03*
X-6280Y42550D03*
G54D231*
X1567064Y522361D03*
X1576796Y523311D03*
X1572495Y598000D03*
G54D123*
X703915Y98272D03*
X1772170Y136750D03*
Y132250D03*
Y127750D03*
Y123250D03*
Y150750D03*
Y146250D03*
Y141250D03*
X1730678Y604617D03*
X1746936Y603249D03*
X1806548Y155437D03*
X1780670Y141250D03*
Y136750D03*
Y132250D03*
Y127750D03*
Y123250D03*
Y150750D03*
Y146250D03*
G54D30*
X29850Y-8062D03*
Y-6487D03*
Y-4912D03*
Y-3337D03*
Y-1762D03*
Y-188D03*
Y1387D03*
Y2962D03*
Y4537D03*
Y6112D03*
G54D141*
X1265488Y322910D03*
X1264182Y315862D03*
X1260234Y328907D03*
G54D150*
X1255730Y314160D03*
G54D132*
X722567Y397000D03*
X741433D03*
G54D12*
X-13406Y73511D03*
Y59763D03*
X1427533Y572491D03*
Y586239D03*
G54D105*
X657250Y-14930D03*
Y3070D03*
X652130Y-14930D03*
Y3070D03*
X654690Y-14930D03*
Y3070D03*
X649570Y-14930D03*
Y3070D03*
X1274050Y109670D03*
Y127670D03*
X1268930Y109670D03*
Y127670D03*
X1271490Y109670D03*
Y127670D03*
X1266370Y109670D03*
Y127670D03*
G54D222*
X1542009Y17268D03*
Y30668D03*
X1545159Y17268D03*
Y30668D03*
X1548309Y17268D03*
Y30668D03*
X1551459Y17268D03*
Y30668D03*
X1554609Y17268D03*
Y30668D03*
X1557759Y17268D03*
Y30668D03*
X1560909Y17268D03*
Y30668D03*
X1564059Y17268D03*
Y30668D03*
X1567209Y17268D03*
Y30668D03*
X1570359Y17268D03*
Y30668D03*
X1573509Y17268D03*
Y30668D03*
X1576659Y17268D03*
Y30668D03*
X1579809Y17268D03*
Y30668D03*
X1582959Y17268D03*
Y30668D03*
X1586109Y17268D03*
Y30668D03*
X1589259Y17268D03*
Y30668D03*
X1592409Y17268D03*
Y30668D03*
X1595559Y17268D03*
Y30668D03*
X1598709Y17268D03*
Y30668D03*
X1601859Y17268D03*
Y30668D03*
X1605009Y17268D03*
Y30668D03*
X1608159Y17268D03*
Y30668D03*
X1611309Y17268D03*
Y30668D03*
X1614459Y17268D03*
Y30668D03*
X1617609Y17268D03*
Y30668D03*
X1620759Y17268D03*
Y30668D03*
X1623909Y17268D03*
Y30668D03*
X1627059Y17268D03*
Y30668D03*
X1630209Y17268D03*
Y30668D03*
X1633359Y17268D03*
Y30668D03*
X1636509Y17268D03*
Y30668D03*
X1639659Y17268D03*
Y30668D03*
X1642809Y17268D03*
Y30668D03*
X1645959Y17268D03*
Y30668D03*
X1649109Y17268D03*
Y30668D03*
X1652259Y17268D03*
Y30668D03*
X1655409Y17268D03*
Y30668D03*
X1658559Y17268D03*
Y30668D03*
X1661709Y17268D03*
Y30668D03*
X1664859Y17268D03*
Y30668D03*
X1668009Y17268D03*
Y30668D03*
X1671159Y17268D03*
Y30668D03*
X1674309Y17268D03*
Y30668D03*
X1677459Y17268D03*
Y30668D03*
X1680609Y17268D03*
Y30668D03*
X1683759Y17268D03*
Y30668D03*
X1686909Y17268D03*
Y30668D03*
X1690059Y17268D03*
Y30668D03*
X1693209Y17268D03*
Y30668D03*
X1696359Y17268D03*
Y30668D03*
X1699509D03*
X1702659Y17268D03*
Y30668D03*
X1705809Y17268D03*
Y30668D03*
X1708959Y17268D03*
Y30668D03*
X1712109Y17268D03*
Y30668D03*
X1699509Y17268D03*
X1715259D03*
Y30668D03*
X1718409Y17268D03*
Y30668D03*
X1721559Y17268D03*
Y30668D03*
X1724709Y17268D03*
Y30668D03*
X1727859Y17268D03*
Y30668D03*
X1731009Y17268D03*
Y30668D03*
X1734159Y17268D03*
Y30668D03*
X1737309Y17268D03*
Y30668D03*
X1740459Y17268D03*
Y30668D03*
X1743609Y17268D03*
Y30668D03*
X1746759Y17268D03*
Y30668D03*
X1749909Y17268D03*
Y30668D03*
X1753059Y17268D03*
Y30668D03*
X1768807Y17268D03*
Y30668D03*
X1771957Y17268D03*
Y30668D03*
X1775107Y17268D03*
Y30668D03*
X1778257Y17268D03*
Y30668D03*
X1781407Y17268D03*
Y30668D03*
X1784557Y17268D03*
Y30668D03*
X1787707Y17268D03*
Y30668D03*
X1790857Y17268D03*
Y30668D03*
X1794007Y17268D03*
Y30668D03*
X1797157Y17268D03*
Y30668D03*
X1800307Y17268D03*
Y30668D03*
X1803457Y17268D03*
Y30668D03*
X1806607Y17268D03*
Y30668D03*
X1809757Y17268D03*
Y30668D03*
X1812907Y17268D03*
Y30668D03*
X1816057Y17268D03*
Y30668D03*
X1819207Y17268D03*
Y30668D03*
X1822357Y17268D03*
Y30668D03*
X1825507Y17268D03*
Y30668D03*
X1828657Y17268D03*
Y30668D03*
X1831807Y17268D03*
Y30668D03*
X1834957Y17268D03*
Y30668D03*
X1853857D03*
X1857007Y17268D03*
Y30668D03*
X1860157Y17268D03*
Y30668D03*
X1863307Y17268D03*
Y30668D03*
X1838107Y17268D03*
X1866457D03*
X1838107Y30668D03*
X1841257Y17268D03*
Y30668D03*
X1844407Y17268D03*
Y30668D03*
X1847557Y17268D03*
Y30668D03*
X1850707Y17268D03*
Y30668D03*
X1853857Y17268D03*
X1866457Y30668D03*
G54D303*
X1933900Y487210D03*
Y482090D03*
Y484650D03*
Y479530D03*
X1923900Y487210D03*
Y484650D03*
Y482090D03*
Y479530D03*
G54D240*
X1630534Y336594D03*
X1628566D03*
X1632503D03*
X1636440D03*
X1634472D03*
Y349698D03*
X1636440D03*
X1628566D03*
X1630534D03*
X1632503D03*
G54D114*
X666327Y387100D03*
Y415100D03*
X1317000Y72800D03*
Y44800D03*
X1295200Y133050D03*
Y105050D03*
X1454600Y584100D03*
Y556100D03*
G54D21*
X43586Y-19703D03*
G54D312*
X1965000Y561500D03*
Y583000D03*
Y604500D03*
G54D204*
X1495325Y381800D03*
X1501175Y385180D03*
Y391940D03*
Y398700D03*
Y378420D03*
X1507025Y388560D03*
Y395320D03*
Y402080D03*
Y381800D03*
X1512875Y385180D03*
Y391940D03*
Y398700D03*
Y378420D03*
X1489475Y398700D03*
X1518725Y388560D03*
Y381800D03*
Y395320D03*
X1522625Y402080D03*
X1524575Y385180D03*
Y391940D03*
Y398700D03*
Y378420D03*
X1489475D03*
Y385180D03*
Y391940D03*
X1495325Y388560D03*
Y395320D03*
Y402080D03*
X1485575Y398700D03*
Y378420D03*
X1497275Y385180D03*
X1520675Y391940D03*
X1505075Y385180D03*
X1520675Y398700D03*
X1487525Y402080D03*
X1505075Y398700D03*
X1491425Y402080D03*
X1493375Y398700D03*
X1497275D03*
X1514825Y395320D03*
Y381800D03*
X1510925Y395320D03*
Y402080D03*
X1508975Y398700D03*
X1516775Y385180D03*
Y391940D03*
Y398700D03*
X1520675Y385180D03*
X1516775Y378420D03*
X1510925Y381800D03*
X1508975Y378420D03*
Y385180D03*
X1510925Y388560D03*
X1514825D03*
X1508975Y391940D03*
X1514825Y402080D03*
X1518725D03*
X1499225D03*
X1503125D03*
X1522625Y381800D03*
X1526525Y395320D03*
X1522625D03*
Y388560D03*
X1526525D03*
Y402080D03*
Y381800D03*
X1520675Y378420D03*
X1491425Y381800D03*
X1499225Y388560D03*
X1493375Y378420D03*
X1505075Y391940D03*
X1497275Y378420D03*
X1493375Y391940D03*
X1497275D03*
X1499225Y381800D03*
X1505075Y378420D03*
X1503125Y388560D03*
Y395320D03*
Y381800D03*
X1499225Y395320D03*
X1487525Y381800D03*
X1485575Y385180D03*
X1493375D03*
X1487525Y388560D03*
X1485575Y391940D03*
X1491425Y388560D03*
X1487525Y395320D03*
X1491425D03*
X1516775Y405460D03*
X1495325Y429120D03*
Y435880D03*
Y449400D03*
X1499225Y435880D03*
Y415600D03*
X1503125Y442640D03*
X1499225Y456160D03*
Y462920D03*
X1501175Y405460D03*
Y412220D03*
Y418980D03*
Y425740D03*
Y432500D03*
Y439260D03*
Y452780D03*
Y459540D03*
X1518725Y456160D03*
X1505075Y459540D03*
X1507025Y408840D03*
X1510925Y456160D03*
X1508975Y405460D03*
Y459540D03*
X1512875Y405460D03*
Y459540D03*
X1516775D03*
X1518725Y408840D03*
X1520675Y459540D03*
X1524575Y405460D03*
Y459540D03*
X1485575Y405460D03*
Y418980D03*
Y432500D03*
Y452780D03*
X1489475Y418980D03*
Y405460D03*
Y432500D03*
Y446020D03*
X1491425Y462920D03*
X1493375Y405460D03*
Y412220D03*
Y418980D03*
Y425740D03*
Y432500D03*
Y439260D03*
X1495325Y442640D03*
Y456160D03*
X1493375Y446020D03*
Y452780D03*
X1495325Y408840D03*
Y415600D03*
Y422360D03*
X1503125D03*
Y429120D03*
Y435880D03*
Y415600D03*
X1520675Y405460D03*
X1526525Y456160D03*
X1514825Y408840D03*
X1510925D03*
X1499225Y442640D03*
Y449400D03*
X1501175Y446020D03*
X1503125Y449400D03*
X1526525Y408840D03*
X1522625D03*
X1514825Y456160D03*
X1503125D03*
X1522625D03*
X1507025D03*
X1497275Y418980D03*
X1499225Y422360D03*
X1497275Y425740D03*
X1499225Y429120D03*
X1497275Y432500D03*
Y452780D03*
Y446020D03*
Y439260D03*
X1503125Y408840D03*
X1505075Y405460D03*
X1499225Y408840D03*
X1497275Y412220D03*
Y405460D03*
X1526525Y462920D03*
X1507025D03*
X1510925D03*
X1503125D03*
X1514825D03*
X1522625D03*
X1518725D03*
X1487525D03*
X1485575Y459540D03*
X1489475D03*
X1495325Y462920D03*
X1493375Y459540D03*
X1487525Y456160D03*
X1491425Y449400D03*
X1497275Y459540D03*
X1491425Y456160D03*
X1489475Y452780D03*
X1487525Y449400D03*
X1485575Y446020D03*
Y412220D03*
X1491425Y422360D03*
X1485575Y439260D03*
X1487525Y442640D03*
X1485575Y425740D03*
X1487525Y429120D03*
Y415600D03*
Y408840D03*
Y435880D03*
X1489475Y412220D03*
X1487525Y422360D03*
X1489475Y439260D03*
X1491425Y442640D03*
X1489475Y425740D03*
X1491425Y429120D03*
Y415600D03*
Y408840D03*
Y435880D03*
X1497275Y479820D03*
X1501175Y466300D03*
X1499225Y469680D03*
X1501175Y486580D03*
X1503125Y469680D03*
X1507025D03*
X1505075Y486580D03*
X1507025Y476440D03*
X1508975Y473060D03*
Y479820D03*
X1514825Y469680D03*
X1512875Y473060D03*
Y479820D03*
Y486580D03*
X1514825Y483200D03*
X1516775Y466300D03*
Y473060D03*
Y479820D03*
Y486580D03*
X1520675Y466300D03*
Y473060D03*
Y486580D03*
X1524575Y466300D03*
Y473060D03*
Y486580D03*
X1526525Y469680D03*
Y476440D03*
X1485575Y473060D03*
Y479820D03*
Y486580D03*
X1487525Y469680D03*
Y483200D03*
X1489475Y473060D03*
X1510925Y469680D03*
X1512875Y466300D03*
X1518725Y476440D03*
X1508975Y466300D03*
X1505075D03*
X1493375Y486580D03*
X1489475D03*
X1493375Y479820D03*
X1491425Y483200D03*
X1499225Y476440D03*
X1497275Y473060D03*
X1489475Y479820D03*
X1487525Y476440D03*
X1491425D03*
X1495325D03*
X1493375Y473060D03*
X1495325Y469680D03*
X1491425D03*
X1489475Y466300D03*
X1485575D03*
X1493375D03*
X1497275D03*
X1510925Y483200D03*
X1508975Y486580D03*
X1505075Y479820D03*
X1507025Y483200D03*
X1503125Y476440D03*
X1501175Y479820D03*
X1503125Y483200D03*
X1499225D03*
X1505075Y473060D03*
X1501175D03*
X1497275Y486580D03*
X1495325Y483200D03*
X1522625Y469680D03*
X1518725D03*
X1514825Y476440D03*
X1510925D03*
X1520675Y479820D03*
X1522625Y476440D03*
Y483200D03*
X1518725D03*
X1524575Y479820D03*
X1526525Y483200D03*
X1565525Y388560D03*
Y395320D03*
Y381800D03*
X1569425Y402080D03*
X1553825Y381800D03*
X1559675Y385180D03*
Y378420D03*
Y391940D03*
Y398700D03*
X1530425Y388560D03*
Y395320D03*
Y402080D03*
Y381800D03*
X1536275Y378420D03*
Y385180D03*
Y391940D03*
Y398700D03*
X1542125Y381800D03*
Y388560D03*
Y395320D03*
X1547975Y378420D03*
Y385180D03*
Y391940D03*
Y398700D03*
X1553825Y388560D03*
Y395320D03*
Y402080D03*
X1540175Y385180D03*
X1555775D03*
X1544075Y391940D03*
X1540175Y398700D03*
X1542125Y402080D03*
X1546025Y381800D03*
X1544075Y378420D03*
X1546025Y388560D03*
X1549925Y402080D03*
X1555775Y378420D03*
X1546025Y395320D03*
X1540175Y391940D03*
X1551875D03*
Y378420D03*
X1549925Y381800D03*
Y395320D03*
X1551875Y398700D03*
X1540175Y378420D03*
X1544075Y398700D03*
X1549925Y388560D03*
X1546025Y402080D03*
X1551875Y385180D03*
X1544075D03*
X1534325Y402080D03*
X1528475Y398700D03*
X1538225Y395320D03*
X1532375Y398700D03*
X1534325Y395320D03*
X1538225Y402080D03*
Y381800D03*
X1528475Y391940D03*
X1532375D03*
X1538225Y388560D03*
X1534325D03*
X1528475Y385180D03*
X1532375D03*
Y378420D03*
X1534325Y381800D03*
X1528475Y378420D03*
X1557725Y402080D03*
X1567475Y385180D03*
X1569425Y388560D03*
X1555775Y398700D03*
X1561625Y395320D03*
X1567475Y378420D03*
X1569425Y381800D03*
X1565525Y402080D03*
X1569425Y395320D03*
X1557725D03*
X1567475Y391940D03*
X1557725Y381800D03*
X1561625Y402080D03*
X1563575Y391940D03*
X1555775D03*
X1561625Y388560D03*
X1557725D03*
X1567475Y398700D03*
X1563575D03*
X1561625Y381800D03*
X1563575Y385180D03*
Y378420D03*
X1561625Y408840D03*
Y415600D03*
Y422360D03*
Y429120D03*
Y435880D03*
Y442640D03*
Y456160D03*
X1563575Y405460D03*
Y439260D03*
Y432500D03*
X1567475D03*
X1565525Y449400D03*
Y456160D03*
X1567475Y405460D03*
Y459540D03*
X1569425Y456160D03*
Y462920D03*
X1555775Y425740D03*
Y452780D03*
X1557725Y415600D03*
Y435880D03*
Y442640D03*
Y449400D03*
Y462920D03*
X1559675Y412220D03*
Y425740D03*
Y459540D03*
X1532375Y405460D03*
Y459540D03*
X1534325Y456160D03*
X1536275Y405460D03*
X1538225Y456160D03*
Y462920D03*
X1540175Y405460D03*
X1542125Y456160D03*
X1544075Y405460D03*
X1546025Y456160D03*
Y462920D03*
X1547975Y405460D03*
X1549925Y408840D03*
Y415600D03*
Y422360D03*
Y429120D03*
Y456160D03*
Y462920D03*
X1551875Y418980D03*
Y425740D03*
Y432500D03*
X1553825Y462920D03*
X1555775Y446020D03*
X1553825Y408840D03*
Y415600D03*
Y435880D03*
Y442640D03*
Y456160D03*
X1528475Y405460D03*
Y459540D03*
X1530425Y456160D03*
Y408840D03*
X1549925Y449400D03*
X1534325Y408840D03*
X1551875Y452780D03*
X1553825Y449400D03*
X1538225Y408840D03*
X1546025D03*
X1551875Y446020D03*
Y439260D03*
Y412220D03*
X1542125Y408840D03*
X1549925Y435880D03*
X1555775Y412220D03*
X1557725Y408840D03*
X1551875Y405460D03*
X1563575Y452780D03*
X1559675D03*
X1547975Y459540D03*
X1536275D03*
X1540175D03*
X1551875D03*
X1555775D03*
X1544075D03*
X1542125Y462920D03*
X1567475Y452780D03*
X1557725Y456160D03*
X1569425Y435880D03*
X1565525D03*
Y442640D03*
X1567475Y446020D03*
X1569425Y449400D03*
X1559675Y446020D03*
X1563575D03*
X1567475Y439260D03*
X1561625Y449400D03*
X1569425Y442640D03*
X1559675Y405460D03*
X1555775D03*
X1567475Y425740D03*
X1563575D03*
X1555775Y439260D03*
X1559675D03*
X1567475Y412220D03*
X1563575D03*
Y418980D03*
X1567475D03*
X1565525Y422360D03*
X1569425D03*
Y429120D03*
X1565525D03*
X1569425Y408840D03*
X1565525D03*
X1569425Y415600D03*
X1565525D03*
X1557725Y429120D03*
X1553825D03*
X1555775Y432500D03*
X1559675D03*
Y418980D03*
X1555775D03*
X1553825Y422360D03*
X1557725D03*
X1549925Y442640D03*
X1530425Y462920D03*
X1534325D03*
X1565525D03*
X1561625D03*
X1563575Y459540D03*
Y479820D03*
X1565525Y469680D03*
X1567475Y473060D03*
Y486580D03*
X1569425Y469680D03*
X1553825D03*
Y476440D03*
Y483200D03*
X1555775Y473060D03*
Y479820D03*
X1530425Y469680D03*
X1532375Y486580D03*
X1534325Y469680D03*
Y483200D03*
X1536275Y473060D03*
X1538225Y476440D03*
X1540175Y473060D03*
X1542125Y469680D03*
Y476440D03*
X1544075Y466300D03*
Y479820D03*
X1546025Y469680D03*
X1547975Y473060D03*
Y486580D03*
X1551875Y466300D03*
Y473060D03*
Y479820D03*
Y486580D03*
X1528475Y473060D03*
X1540175Y466300D03*
X1538225Y469680D03*
X1532375Y466300D03*
X1528475D03*
X1536275D03*
X1563575Y486580D03*
X1561625Y483200D03*
X1569425D03*
X1565525D03*
X1567475Y479820D03*
X1569425Y476440D03*
X1561625D03*
X1557725D03*
X1547975Y466300D03*
X1549925Y469680D03*
X1544075Y486580D03*
X1542125Y483200D03*
X1549925D03*
X1546025D03*
Y476440D03*
X1544075Y473060D03*
X1549925Y476440D03*
X1547975Y479820D03*
X1559675D03*
X1557725Y483200D03*
X1559675Y486580D03*
X1555775D03*
X1530425Y476440D03*
X1532375Y473060D03*
X1528475Y479820D03*
X1532375D03*
X1530425Y483200D03*
X1528475Y486580D03*
X1536275Y479820D03*
X1534325Y476440D03*
X1540175Y486580D03*
X1536275D03*
X1538225Y483200D03*
X1540175Y479820D03*
X1565525Y476440D03*
X1563575Y473060D03*
X1559675D03*
X1561625Y469680D03*
X1555775Y466300D03*
X1557725Y469680D03*
X1567475Y466300D03*
X1559675D03*
X1563575D03*
G54D213*
X1481729Y592414D03*
X1517267Y593682D03*
G54D313*
G01X430749Y-124922D02*
G02I-12000J0D01*
G01X425599D02*
G02I-6850J0D01*
G01X434749D02*
X402749D01*
G01X434749Y-140922D02*
Y-220922D01*
G01D02*
X1729349D01*
G01X434749Y-176422D02*
X1729349D01*
G01X418749Y-140922D02*
Y-108922D01*
G01X434749Y-140922D02*
X1729349D01*
G01X941849D02*
Y-220922D01*
G01X1079349Y-140922D02*
Y-220922D01*
G01X1194349Y-140922D02*
Y-220922D01*
G01X1361849Y-140922D02*
Y-220922D01*
G01X1531849Y-140922D02*
Y-220922D01*
G01X1729349Y-140922D02*
Y-220922D01*
G01X1757349Y-124922D02*
G02I-12000J0D01*
G01X1752199D02*
G02I-6850J0D01*
G01X1745349Y-140922D02*
Y-108922D01*
G01X1761349Y-124922D02*
X1729349D01*
G54D124*
X700515Y98272D03*
X1768770Y136750D03*
Y132250D03*
Y127750D03*
Y123250D03*
Y150750D03*
Y146250D03*
Y141250D03*
X1727278Y604617D03*
X1743536Y603249D03*
X1803148Y155437D03*
X1777270Y141250D03*
Y136750D03*
Y132250D03*
Y127750D03*
Y123250D03*
Y150750D03*
Y146250D03*
G54D31*
X32413Y8675D03*
X33988D03*
X35563D03*
X37138D03*
X38713D03*
X40287D03*
X41862D03*
X43437D03*
X45012D03*
X46587D03*
G54D250*
X1670306Y231988D03*
X1676982Y227010D03*
X1902513Y197965D03*
G54D142*
X1256754Y321327D03*
X1261585Y307408D03*
G54D151*
X1248995Y302830D03*
G54D115*
X634930Y487050D03*
X616930D03*
X634930Y481930D03*
X616930D03*
X634930Y484490D03*
X616930D03*
X634930Y479370D03*
X616930D03*
G54D223*
X1587664Y138614D03*
X1540980Y350955D03*
X1863358Y138108D03*
G54D241*
X1599227Y388133D03*
X1607495Y394433D03*
X1599227D03*
X1607495Y388133D03*
G54D205*
X1484193Y371161D03*
X1481105D03*
X1475098Y381068D03*
X1487879Y368287D03*
X1477972Y374294D03*
Y377382D03*
X1484193Y493839D03*
X1481105D03*
X1475098Y483932D03*
X1487879Y496713D03*
X1477972Y487618D03*
Y490706D03*
X1573895Y371161D03*
X1570807D03*
X1567121Y368287D03*
X1579902Y381068D03*
X1577028Y377382D03*
Y374294D03*
X1573895Y493839D03*
X1570807D03*
X1567121Y496713D03*
X1579902Y483932D03*
X1577028Y490706D03*
Y487618D03*
G54D106*
X655500Y57400D03*
X655600Y543750D03*
X677000Y57400D03*
X677100Y543750D03*
X1314300Y116800D03*
X1335800D03*
X1308150Y529500D03*
X1329650D03*
X1589980Y270040D03*
X1568480D03*
G54D214*
X1475723Y602756D03*
X1511261Y604024D03*
G54D22*
X46986Y-19703D03*
G54D133*
X721319Y496250D03*
X1394664Y544352D03*
X1541300Y316800D03*
X1634350Y204750D03*
X1736689Y173231D03*
X1732189D03*
X1727689D03*
X1723189D03*
Y165731D03*
X1727689D03*
X1732189D03*
X1736689D03*
X1718689D03*
Y173181D03*
X1714189Y165731D03*
X1855663Y145648D03*
G54D160*
X1255969Y462926D03*
X1251312Y459613D03*
G54D304*
X1952756Y589960D03*
X1944882Y582086D03*
X1952756D03*
X1944882Y574212D03*
X1952756D03*
X1944882Y566338D03*
X1952756D03*
X1944882Y558464D03*
Y589960D03*
Y605708D03*
X1952756D03*
X1944882Y597834D03*
X1952756D03*
G54D232*
X1627642Y-14488D03*
X1647327Y-315D03*
G54D40*
X24582Y-3053D03*
X225718Y130200D03*
X222829Y141300D03*
X210896Y140300D03*
X213828Y134900D03*
X195800Y124600D03*
X200900Y120704D03*
X231492Y140500D03*
X239892Y135000D03*
X242592Y142000D03*
X267186Y141000D03*
X270504Y136000D03*
X234192Y134000D03*
X256492Y130000D03*
X259149Y140500D03*
X249872Y141500D03*
X252612Y135500D03*
X245292Y125500D03*
X251642Y123500D03*
X333692Y110190D03*
X329573Y107022D03*
X353714Y103936D03*
X347592Y103993D03*
X345492Y112063D03*
X329730Y489798D03*
X384377Y114881D03*
X378422Y106505D03*
X375287Y127696D03*
X360617Y103689D03*
X377272Y116996D03*
X363186Y108014D03*
X374137Y140732D03*
X382392Y109922D03*
X405733Y104472D03*
X412792Y104540D03*
X377149Y462175D03*
X380350Y453103D03*
X372781Y491333D03*
X377192Y498249D03*
X403192Y498191D03*
X419092Y104695D03*
X474326Y112500D03*
X466112Y114000D03*
X460292Y115000D03*
X467262Y109000D03*
X425492Y104752D03*
X481691Y104000D03*
X496902Y116000D03*
X516442Y130500D03*
X521052Y117000D03*
X508892Y122500D03*
X511492Y133000D03*
X533203Y119500D03*
X524392Y132500D03*
X526911Y125000D03*
X537511Y135500D03*
X557692Y133500D03*
X560211Y140500D03*
X547328Y120500D03*
X555147Y139000D03*
X540992Y141000D03*
X543659Y126500D03*
X544809Y135000D03*
X847304Y138000D03*
X861026Y141000D03*
X858337Y125500D03*
X850036Y128500D03*
X889500Y135000D03*
X892200Y142000D03*
X881100Y140500D03*
X883800Y134000D03*
X906100Y130000D03*
X908757Y140500D03*
X899480Y141500D03*
X902220Y135500D03*
X894900Y125500D03*
X901250Y123500D03*
X916794Y141000D03*
X920112Y136000D03*
X945300Y140000D03*
X948000Y130500D03*
X936900Y135000D03*
X926300Y142500D03*
X929100Y137500D03*
X1033985Y115181D03*
X983300Y110390D03*
X979181Y107022D03*
X1028030Y115156D03*
X1024895Y111035D03*
X1010225Y103689D03*
X1026880Y103936D03*
X1012794Y108014D03*
X1032000Y110422D03*
X1003322Y103936D03*
X997200Y103793D03*
X995100Y112669D03*
X1003580Y138417D03*
X1026757Y461106D03*
X1029958Y451876D03*
X979338Y490843D03*
X1022389Y490150D03*
X1026800Y497824D03*
X1081732Y104117D03*
X1068700Y104697D03*
X1055341Y104472D03*
X1062400Y104568D03*
X1075100Y104812D03*
X1055670Y464870D03*
X1052800Y498443D03*
X1051700Y476126D03*
X1059640Y474572D03*
X1047730Y470954D03*
X1131299Y104000D03*
X1123934Y112500D03*
X1109900Y115000D03*
X1116870Y109000D03*
X1146510Y115200D03*
X1166050Y130500D03*
X1170660Y117000D03*
X1158500Y122500D03*
X1161100Y133000D03*
X1182811Y119500D03*
X1207300Y133500D03*
X1209819Y140500D03*
X1174000Y132500D03*
X1176519Y125000D03*
X1196936Y120500D03*
X1204755Y139000D03*
X1190600Y141000D03*
X1193267Y126500D03*
X1187119Y135500D03*
X1194417Y135000D03*
X1202961Y464997D03*
X1190650Y466472D03*
X1194970Y474489D03*
X1359657Y96096D03*
X1354309Y505157D03*
X1349000Y505800D03*
X1563712Y590349D03*
G54D13*
X-15300Y255000D03*
X13700D03*
G54D314*
G01X548049Y-193422D02*
Y-210922D01*
G01X543027Y-193422D02*
X553071D01*
G01X565549Y-199256D02*
Y-210922D01*
G01Y-194589D02*
X565112Y-194297D01*
Y-193714D01*
X565549Y-193422D01*
X565986Y-193714D01*
Y-194297D01*
X565549Y-194589D01*
G01X583049Y-210922D02*
X581739Y-210630D01*
X580429Y-209464D01*
X579555Y-207422D01*
X579119Y-205089D01*
X579555Y-202755D01*
X580429Y-200714D01*
X581739Y-199547D01*
X583049Y-199256D01*
X584359Y-199547D01*
X585669Y-200714D01*
X586542Y-202755D01*
X586761Y-205089D01*
X586542Y-207422D01*
X585669Y-209464D01*
X584359Y-210630D01*
X583049Y-210922D01*
G01X597492Y-215297D02*
X599021Y-216464D01*
X600767Y-216755D01*
X602295Y-216464D01*
X603606Y-215006D01*
X604479Y-212964D01*
Y-199256D01*
G01Y-201589D02*
X603606Y-200422D01*
X602295Y-199547D01*
X600767Y-199256D01*
X599021Y-199839D01*
X597929Y-201005D01*
X597055Y-203047D01*
X596619Y-205089D01*
X596837Y-206839D01*
X597711Y-208881D01*
X599021Y-210339D01*
X600767Y-210922D01*
X602077Y-210630D01*
X603606Y-209464D01*
X604479Y-208298D01*
G01X621979Y-210922D02*
Y-199256D01*
G01Y-201297D02*
X621106Y-200131D01*
X619795Y-199547D01*
X618267Y-199256D01*
X616739Y-199839D01*
X615429Y-201005D01*
X614555Y-202755D01*
X614119Y-205089D01*
X614555Y-207422D01*
X615429Y-209172D01*
X616739Y-210339D01*
X618267Y-210922D01*
X619795Y-210630D01*
X621106Y-209756D01*
X621979Y-208589D01*
G01X648682Y-210922D02*
Y-193422D01*
X653922D01*
X655669Y-194297D01*
X656979Y-196339D01*
X657416Y-198672D01*
X656979Y-201005D01*
X655887Y-202755D01*
X653922Y-203631D01*
X648682D01*
G01X674479Y-210922D02*
Y-199256D01*
G01Y-201297D02*
X673606Y-200131D01*
X672295Y-199547D01*
X670767Y-199256D01*
X669239Y-199839D01*
X667929Y-201005D01*
X667055Y-202755D01*
X666619Y-205089D01*
X667055Y-207422D01*
X667929Y-209172D01*
X669239Y-210339D01*
X670767Y-210922D01*
X672295Y-210630D01*
X673606Y-209756D01*
X674479Y-208589D01*
G01X684774Y-208881D02*
X685866Y-210047D01*
X687394Y-210922D01*
X688704D01*
X690014Y-210339D01*
X690887Y-209464D01*
X691324Y-208298D01*
X691106Y-206547D01*
X690232Y-205672D01*
X686302Y-203922D01*
X685429Y-201880D01*
X685866Y-200422D01*
X686739Y-199547D01*
X688049Y-199256D01*
X689359Y-199547D01*
X690669Y-200422D01*
G01X702274Y-208881D02*
X703366Y-210047D01*
X704894Y-210922D01*
X706204D01*
X707514Y-210339D01*
X708387Y-209464D01*
X708824Y-208298D01*
X708606Y-206547D01*
X707732Y-205672D01*
X703802Y-203922D01*
X702929Y-201880D01*
X703366Y-200422D01*
X704239Y-199547D01*
X705549Y-199256D01*
X706859Y-199547D01*
X708169Y-200422D01*
G01X735746Y-210922D02*
Y-193422D01*
X740112D01*
X741859Y-194297D01*
X743169Y-195464D01*
X744261Y-197213D01*
X745134Y-199256D01*
X745352Y-202172D01*
X745134Y-205089D01*
X744261Y-207131D01*
X743169Y-208881D01*
X741859Y-210047D01*
X740112Y-210922D01*
X735746D01*
G01X752590Y-193422D02*
X758049Y-210922D01*
X763508Y-193422D01*
G01X775549D02*
Y-210922D01*
G01X770527Y-193422D02*
X780571D01*
G01X804872Y-210922D02*
Y-193422D01*
X810549Y-208005D01*
X816226Y-193422D01*
Y-210922D01*
G01X829795Y-201589D02*
X830669Y-200714D01*
X831324Y-199256D01*
X831761Y-197213D01*
X831324Y-195464D01*
X830451Y-194297D01*
X828922Y-193422D01*
X823027D01*
Y-210922D01*
X830232D01*
X831761Y-209756D01*
X832634Y-208005D01*
X833071Y-205964D01*
X832634Y-203922D01*
X831324Y-202172D01*
X829795Y-201589D01*
X823027D01*
G01X647372Y-165922D02*
Y-148422D01*
X653049Y-163005D01*
X658726Y-148422D01*
Y-165922D01*
G01X670549D02*
X669239Y-165630D01*
X667929Y-164464D01*
X667055Y-162422D01*
X666619Y-160089D01*
X667055Y-157755D01*
X667929Y-155714D01*
X669239Y-154547D01*
X670549Y-154256D01*
X671859Y-154547D01*
X673169Y-155714D01*
X674042Y-157755D01*
X674261Y-160089D01*
X674042Y-162422D01*
X673169Y-164464D01*
X671859Y-165630D01*
X670549Y-165922D01*
G01X691979Y-148422D02*
Y-165922D01*
G01Y-163298D02*
X691106Y-164756D01*
X689795Y-165630D01*
X688267Y-165922D01*
X686521Y-165339D01*
X685211Y-163881D01*
X684337Y-162131D01*
X684119Y-160089D01*
X684337Y-158047D01*
X685211Y-156297D01*
X686521Y-154839D01*
X688267Y-154256D01*
X689795Y-154547D01*
X690887Y-155131D01*
X691979Y-156297D01*
G01X702274Y-158047D02*
X709261D01*
X708606Y-156005D01*
X707514Y-154839D01*
X705986Y-154256D01*
X704457Y-154547D01*
X703147Y-155422D01*
X702274Y-157464D01*
X701837Y-159214D01*
Y-160964D01*
X702274Y-162714D01*
X703366Y-164464D01*
X704676Y-165630D01*
X706204Y-165922D01*
X707732Y-165339D01*
X709261Y-163589D01*
G01X723049Y-165922D02*
Y-148422D01*
G01X975549Y-210922D02*
Y-193422D01*
X972929Y-196922D01*
G01Y-210922D02*
X978169D01*
G01X988246Y-208298D02*
X989555Y-209756D01*
X991084Y-210630D01*
X993049Y-210922D01*
X995014Y-210339D01*
X996542Y-209172D01*
X997634Y-207131D01*
X997852Y-204797D01*
X997416Y-202464D01*
X996324Y-201005D01*
X994795Y-199839D01*
X993267Y-199547D01*
X991739Y-199839D01*
X989774Y-201005D01*
X990429Y-193422D01*
X996324D01*
G01X1010549Y-210922D02*
Y-193422D01*
X1007929Y-196922D01*
G01Y-210922D02*
X1013169D01*
G01X1023901Y-196339D02*
X1025211Y-194589D01*
X1026739Y-193714D01*
X1028486Y-193422D01*
X1030669Y-194005D01*
X1032197Y-195464D01*
X1032634Y-197213D01*
X1032416Y-198964D01*
X1031542Y-200422D01*
X1027176Y-203339D01*
X1025211Y-205380D01*
X1023901Y-208298D01*
X1023464Y-210922D01*
X1032634D01*
G01X1041401Y-203631D02*
X1042929Y-201589D01*
X1044239Y-200422D01*
X1045986Y-199839D01*
X1047514Y-200422D01*
X1048606Y-201589D01*
X1049479Y-203339D01*
X1049697Y-205380D01*
X1049479Y-207131D01*
X1048606Y-208881D01*
X1047295Y-210339D01*
X1045767Y-210922D01*
X1044021Y-210339D01*
X1042492Y-208589D01*
X1041619Y-205964D01*
X1041401Y-203047D01*
X1041837Y-199256D01*
X1042492Y-197213D01*
X1043584Y-195172D01*
X1045112Y-193714D01*
X1046641Y-193422D01*
X1048169Y-194005D01*
X1049261Y-195464D01*
G01X962432Y-165922D02*
Y-148422D01*
X967672D01*
X969419Y-149297D01*
X970729Y-151339D01*
X971166Y-153672D01*
X970729Y-156005D01*
X969637Y-157755D01*
X967672Y-158631D01*
X962432D01*
G01X989102Y-149881D02*
X987792Y-149005D01*
X986264Y-148422D01*
X984517D01*
X982552Y-149297D01*
X981024Y-150755D01*
X979932Y-152506D01*
X979059Y-155422D01*
X978840Y-158047D01*
X979277Y-160672D01*
X979932Y-162422D01*
X981242Y-164172D01*
X982771Y-165339D01*
X984299Y-165922D01*
X985827D01*
X987356Y-165339D01*
X988666Y-164464D01*
X989758Y-163298D01*
G01X1003545Y-156589D02*
X1004419Y-155714D01*
X1005074Y-154256D01*
X1005511Y-152213D01*
X1005074Y-150464D01*
X1004201Y-149297D01*
X1002672Y-148422D01*
X996777D01*
Y-165922D01*
X1003982D01*
X1005511Y-164756D01*
X1006384Y-163005D01*
X1006821Y-160964D01*
X1006384Y-158922D01*
X1005074Y-157172D01*
X1003545Y-156589D01*
X996777D01*
G01X1012749Y-171755D02*
X1025849D01*
G01X1031777Y-165922D02*
Y-148422D01*
X1041821Y-165922D01*
Y-148422D01*
G01X1054299Y-165922D02*
X1052552Y-165630D01*
X1051024Y-164464D01*
X1049714Y-162714D01*
X1048840Y-160672D01*
X1048404Y-158339D01*
Y-156005D01*
X1048840Y-153672D01*
X1049714Y-151630D01*
X1051024Y-149881D01*
X1052552Y-148714D01*
X1054299Y-148422D01*
X1056045Y-148714D01*
X1057574Y-149881D01*
X1058884Y-151630D01*
X1059758Y-153672D01*
X1060194Y-156005D01*
Y-158339D01*
X1059758Y-160672D01*
X1058884Y-162714D01*
X1057574Y-164464D01*
X1056045Y-165630D01*
X1054299Y-165922D01*
G01X1128099Y-210922D02*
Y-193422D01*
X1125479Y-196922D01*
G01Y-210922D02*
X1130719D01*
G01X1147345Y-201589D02*
X1148219Y-200714D01*
X1148874Y-199256D01*
X1149311Y-197213D01*
X1148874Y-195464D01*
X1148001Y-194297D01*
X1146472Y-193422D01*
X1140577D01*
Y-210922D01*
X1147782D01*
X1149311Y-209756D01*
X1150184Y-208005D01*
X1150621Y-205964D01*
X1150184Y-203922D01*
X1148874Y-202172D01*
X1147345Y-201589D01*
X1140577D01*
G01X1105140Y-148422D02*
X1110599Y-165922D01*
X1116058Y-148422D01*
G01X1132466Y-165922D02*
X1123732D01*
Y-148422D01*
X1132466D01*
G01X1128972Y-156880D02*
X1123732D01*
G01X1141232Y-165922D02*
Y-148422D01*
X1146691D01*
X1148437Y-149297D01*
X1149529Y-150464D01*
X1149966Y-152797D01*
X1149529Y-155131D01*
X1148219Y-156589D01*
X1146691Y-157464D01*
X1141232D01*
G01X1146691D02*
X1149966Y-165922D01*
G01X1163099Y-166505D02*
X1162662Y-166214D01*
Y-165630D01*
X1163099Y-165339D01*
X1163536Y-165630D01*
Y-166214D01*
X1163099Y-166505D01*
G01X1251799Y-193422D02*
Y-210922D01*
G01X1246777Y-193422D02*
X1256821D01*
G01X1264714Y-208589D02*
X1266461Y-210047D01*
X1268426Y-210922D01*
X1270172D01*
X1271919Y-210047D01*
X1273229Y-208589D01*
X1273884Y-206547D01*
X1273447Y-204506D01*
X1272356Y-202755D01*
X1270391Y-201589D01*
X1267771Y-201005D01*
X1266242Y-199839D01*
X1265587Y-197797D01*
X1266024Y-195755D01*
X1267116Y-194297D01*
X1268644Y-193422D01*
X1270172D01*
X1271701Y-194005D01*
X1273011Y-195464D01*
G01X1281122Y-210922D02*
Y-193422D01*
X1286799Y-208005D01*
X1292476Y-193422D01*
Y-210922D01*
G01X1299496D02*
Y-193422D01*
X1303862D01*
X1305609Y-194297D01*
X1306919Y-195464D01*
X1308011Y-197213D01*
X1308884Y-199256D01*
X1309102Y-202172D01*
X1308884Y-205089D01*
X1308011Y-207131D01*
X1306919Y-208881D01*
X1305609Y-210047D01*
X1303862Y-210922D01*
X1299496D01*
G01X1238682Y-148422D02*
Y-165922D01*
X1247416D01*
G01X1264479D02*
Y-154256D01*
G01Y-156297D02*
X1263606Y-155131D01*
X1262295Y-154547D01*
X1260767Y-154256D01*
X1259239Y-154839D01*
X1257929Y-156005D01*
X1257055Y-157755D01*
X1256619Y-160089D01*
X1257055Y-162422D01*
X1257929Y-164172D01*
X1259239Y-165339D01*
X1260767Y-165922D01*
X1262295Y-165630D01*
X1263606Y-164756D01*
X1264479Y-163589D01*
G01X1273464Y-171172D02*
X1274774Y-171755D01*
X1276521Y-171172D01*
X1277612Y-170006D01*
X1278486Y-168547D01*
X1279795Y-163881D01*
X1282634Y-154256D01*
G01X1275647D02*
X1279795Y-163881D01*
G01X1292274Y-158047D02*
X1299261D01*
X1298606Y-156005D01*
X1297514Y-154839D01*
X1295986Y-154256D01*
X1294457Y-154547D01*
X1293147Y-155422D01*
X1292274Y-157464D01*
X1291837Y-159214D01*
Y-160964D01*
X1292274Y-162714D01*
X1293366Y-164464D01*
X1294676Y-165630D01*
X1296204Y-165922D01*
X1297732Y-165339D01*
X1299261Y-163589D01*
G01X1309992Y-165922D02*
Y-154256D01*
G01Y-156589D02*
X1311084Y-155422D01*
X1312176Y-154547D01*
X1313704Y-154256D01*
X1314795Y-154547D01*
X1316106Y-155422D01*
G01X1380796Y-165922D02*
Y-148422D01*
X1385162D01*
X1386909Y-149297D01*
X1388219Y-150464D01*
X1389311Y-152213D01*
X1390184Y-154256D01*
X1390402Y-157172D01*
X1390184Y-160089D01*
X1389311Y-162131D01*
X1388219Y-163881D01*
X1386909Y-165047D01*
X1385162Y-165922D01*
X1380796D01*
G01X1399824Y-158047D02*
X1406811D01*
X1406156Y-156005D01*
X1405064Y-154839D01*
X1403536Y-154256D01*
X1402007Y-154547D01*
X1400697Y-155422D01*
X1399824Y-157464D01*
X1399387Y-159214D01*
Y-160964D01*
X1399824Y-162714D01*
X1400916Y-164464D01*
X1402226Y-165630D01*
X1403754Y-165922D01*
X1405282Y-165339D01*
X1406811Y-163589D01*
G01X1417324Y-163881D02*
X1418416Y-165047D01*
X1419944Y-165922D01*
X1421254D01*
X1422564Y-165339D01*
X1423437Y-164464D01*
X1423874Y-163298D01*
X1423656Y-161547D01*
X1422782Y-160672D01*
X1418852Y-158922D01*
X1417979Y-156880D01*
X1418416Y-155422D01*
X1419289Y-154547D01*
X1420599Y-154256D01*
X1421909Y-154547D01*
X1423219Y-155422D01*
G01X1438099Y-154256D02*
Y-165922D01*
G01Y-149589D02*
X1437662Y-149297D01*
Y-148714D01*
X1438099Y-148422D01*
X1438536Y-148714D01*
Y-149297D01*
X1438099Y-149589D01*
G01X1452542Y-170297D02*
X1454071Y-171464D01*
X1455817Y-171755D01*
X1457345Y-171464D01*
X1458656Y-170006D01*
X1459529Y-167964D01*
Y-154256D01*
G01Y-156589D02*
X1458656Y-155422D01*
X1457345Y-154547D01*
X1455817Y-154256D01*
X1454071Y-154839D01*
X1452979Y-156005D01*
X1452105Y-158047D01*
X1451669Y-160089D01*
X1451887Y-161839D01*
X1452761Y-163881D01*
X1454071Y-165339D01*
X1455817Y-165922D01*
X1457127Y-165630D01*
X1458656Y-164464D01*
X1459529Y-163298D01*
G01X1469387Y-165922D02*
Y-154256D01*
G01Y-157172D02*
X1470261Y-155714D01*
X1471571Y-154547D01*
X1473317Y-154256D01*
X1474845Y-154547D01*
X1476156Y-155714D01*
X1476811Y-157755D01*
Y-165922D01*
G01X1487324Y-158047D02*
X1494311D01*
X1493656Y-156005D01*
X1492564Y-154839D01*
X1491036Y-154256D01*
X1489507Y-154547D01*
X1488197Y-155422D01*
X1487324Y-157464D01*
X1486887Y-159214D01*
Y-160964D01*
X1487324Y-162714D01*
X1488416Y-164464D01*
X1489726Y-165630D01*
X1491254Y-165922D01*
X1492782Y-165339D01*
X1494311Y-163589D01*
G01X1505042Y-165922D02*
Y-154256D01*
G01Y-156589D02*
X1506134Y-155422D01*
X1507226Y-154547D01*
X1508754Y-154256D01*
X1509845Y-154547D01*
X1511156Y-155422D01*
G01X1426729Y-193422D02*
X1431969D01*
G01X1429349D02*
Y-210922D01*
G01X1426729D02*
X1431969D01*
G01X1441390Y-193422D02*
X1446849Y-210922D01*
X1452308Y-193422D01*
G01X1464349Y-210922D02*
Y-203047D01*
X1459982Y-193422D01*
G01X1468716D02*
X1464349Y-203047D01*
G01X1551799Y-193422D02*
X1550052Y-194005D01*
X1548742Y-195464D01*
X1547869Y-197213D01*
X1547214Y-199547D01*
X1546996Y-202172D01*
X1547214Y-204797D01*
X1547869Y-207131D01*
X1548742Y-208881D01*
X1550052Y-210339D01*
X1551799Y-210922D01*
X1553545Y-210339D01*
X1554856Y-208881D01*
X1555729Y-207131D01*
X1556384Y-204797D01*
X1556602Y-202172D01*
X1556384Y-199547D01*
X1555729Y-197213D01*
X1554856Y-195464D01*
X1553545Y-194005D01*
X1551799Y-193422D01*
G01X1565151Y-196339D02*
X1566461Y-194589D01*
X1567989Y-193714D01*
X1569736Y-193422D01*
X1571919Y-194005D01*
X1573447Y-195464D01*
X1573884Y-197213D01*
X1573666Y-198964D01*
X1572792Y-200422D01*
X1568426Y-203339D01*
X1566461Y-205380D01*
X1565151Y-208298D01*
X1564714Y-210922D01*
X1573884D01*
G01X1582869Y-211505D02*
X1590729Y-193422D01*
G01X1604299Y-210922D02*
Y-193422D01*
X1601679Y-196922D01*
G01Y-210922D02*
X1606919D01*
G01X1621799Y-193422D02*
X1620052Y-194005D01*
X1618742Y-195464D01*
X1617869Y-197213D01*
X1617214Y-199547D01*
X1616996Y-202172D01*
X1617214Y-204797D01*
X1617869Y-207131D01*
X1618742Y-208881D01*
X1620052Y-210339D01*
X1621799Y-210922D01*
X1623545Y-210339D01*
X1624856Y-208881D01*
X1625729Y-207131D01*
X1626384Y-204797D01*
X1626602Y-202172D01*
X1626384Y-199547D01*
X1625729Y-197213D01*
X1624856Y-195464D01*
X1623545Y-194005D01*
X1621799Y-193422D01*
G01X1635369Y-211505D02*
X1643229Y-193422D01*
G01X1652651Y-196339D02*
X1653961Y-194589D01*
X1655489Y-193714D01*
X1657236Y-193422D01*
X1659419Y-194005D01*
X1660947Y-195464D01*
X1661384Y-197213D01*
X1661166Y-198964D01*
X1660292Y-200422D01*
X1655926Y-203339D01*
X1653961Y-205380D01*
X1652651Y-208298D01*
X1652214Y-210922D01*
X1661384D01*
G01X1674299Y-193422D02*
X1672552Y-194005D01*
X1671242Y-195464D01*
X1670369Y-197213D01*
X1669714Y-199547D01*
X1669496Y-202172D01*
X1669714Y-204797D01*
X1670369Y-207131D01*
X1671242Y-208881D01*
X1672552Y-210339D01*
X1674299Y-210922D01*
X1676045Y-210339D01*
X1677356Y-208881D01*
X1678229Y-207131D01*
X1678884Y-204797D01*
X1679102Y-202172D01*
X1678884Y-199547D01*
X1678229Y-197213D01*
X1677356Y-195464D01*
X1676045Y-194005D01*
X1674299Y-193422D01*
G01X1691799Y-210922D02*
Y-193422D01*
X1689179Y-196922D01*
G01Y-210922D02*
X1694419D01*
G01X1708862D02*
X1709299Y-207131D01*
X1709954Y-203922D01*
X1710827Y-201005D01*
X1711919Y-197797D01*
X1713666Y-193422D01*
X1704932D01*
G01X1599496Y-165922D02*
Y-148422D01*
X1603862D01*
X1605609Y-149297D01*
X1606919Y-150464D01*
X1608011Y-152213D01*
X1608884Y-154256D01*
X1609102Y-157172D01*
X1608884Y-160089D01*
X1608011Y-162131D01*
X1606919Y-163881D01*
X1605609Y-165047D01*
X1603862Y-165922D01*
X1599496D01*
G01X1625729D02*
Y-154256D01*
G01Y-156297D02*
X1624856Y-155131D01*
X1623545Y-154547D01*
X1622017Y-154256D01*
X1620489Y-154839D01*
X1619179Y-156005D01*
X1618305Y-157755D01*
X1617869Y-160089D01*
X1618305Y-162422D01*
X1619179Y-164172D01*
X1620489Y-165339D01*
X1622017Y-165922D01*
X1623545Y-165630D01*
X1624856Y-164756D01*
X1625729Y-163589D01*
G01X1639299Y-148422D02*
Y-165922D01*
G01X1636242Y-154256D02*
X1642356D01*
G01X1653524Y-158047D02*
X1660511D01*
X1659856Y-156005D01*
X1658764Y-154839D01*
X1657236Y-154256D01*
X1655707Y-154547D01*
X1654397Y-155422D01*
X1653524Y-157464D01*
X1653087Y-159214D01*
Y-160964D01*
X1653524Y-162714D01*
X1654616Y-164464D01*
X1655926Y-165630D01*
X1657454Y-165922D01*
X1658982Y-165339D01*
X1660511Y-163589D01*
G01X-7874Y-31496D02*
X-19685D01*
G01X-7874D02*
X-19685D01*
G01D02*
G03X-23622Y-35433I0J-3937D01*
G01D02*
Y-59055D01*
G01Y-35433D02*
Y-59055D01*
G01X-19685Y-31496D02*
G03X-23622Y-35433I0J-3937D01*
G01Y-59055D02*
G03X-19685Y-62992I3937J0D01*
G01D02*
X1972441D01*
G01X-19685D02*
X1972441D01*
G01X-23622Y-59055D02*
G03X-19685Y-62992I3937J0D01*
G01Y-23622D02*
X1972441D01*
G01X-19685D02*
X1972441D01*
G01X-19685D02*
X1972441D01*
G01X-19685D02*
X1972441D01*
G01X-23622Y622441D02*
Y-19685D01*
G01Y622441D02*
Y-19685D01*
G01Y622441D02*
Y-19685D01*
G01Y622441D02*
Y-19685D01*
G01D02*
G03X-19685Y-23622I3937J0D01*
G01X-23622Y-19685D02*
G03X-19685Y-23622I3937J0D01*
G01X-23622Y-19685D02*
G03X-19685Y-23622I3937J0D01*
G01X-23622Y-19685D02*
G03X-19685Y-23622I3937J0D01*
G01X1972441Y626378D02*
X-19685D01*
G01X1972441D02*
X-19685D01*
G01X1972441D02*
X-19685D01*
G01X1972441D02*
X-19685D01*
G01D02*
G03X-23622Y622441I0J-3937D01*
G01X-19685Y626378D02*
G03X-23622Y622441I0J-3937D01*
G01X-19685Y626378D02*
G03X-23622Y622441I0J-3937D01*
G01X-19685Y626378D02*
G03X-23622Y622441I0J-3937D01*
G01X-19685Y634252D02*
X-7874D01*
G01X-19685D02*
X-7874D01*
G01X-23622Y661811D02*
Y638189D01*
G01Y661811D02*
Y638189D01*
G01D02*
G03X-19685Y634252I3937J0D01*
G01X-23622Y638189D02*
G03X-19685Y634252I3937J0D01*
G01X1972441Y665748D02*
X-19685D01*
G01X1972441D02*
X-19685D01*
G01D02*
G03X-23622Y661811I0J-3937D01*
G01X-19685Y665748D02*
G03X-23622Y661811I0J-3937D01*
G01X-7874Y-31496D02*
G03Y-23622I0J3937D01*
G01Y-31496D02*
G03Y-23622I0J3937D01*
G01X22835D02*
G03Y-31496I0J-3937D01*
G01X137795D02*
X22835D01*
G01X137795D02*
X22835D01*
G01Y-23622D02*
G03Y-31496I0J-3937D01*
G01X0Y616535D02*
G03Y604724I0J-5905D01*
G01Y616535D02*
G03Y604724I0J-5905D01*
G01Y616535D02*
X2646D01*
G01X2644D02*
X0D01*
G01Y604724D02*
X2644D01*
G01X2646D02*
X0D01*
G01X2646D02*
X0D01*
G01D02*
X2644D01*
G01Y616535D02*
X0D01*
G01D02*
X2646D01*
G01X0D02*
G03Y604724I0J-5905D01*
G01Y616535D02*
G03Y604724I0J-5905D01*
G01X2646Y616535D02*
G03X7595Y618285I0J7874D01*
G01X2644Y616535D02*
G03X7593Y618285I0J7874D01*
G01X2644Y616535D02*
G03X7593Y618285I0J7874D01*
G01X7595Y602975D02*
G03X2646Y604724I-4948J-6125D01*
G01X7593Y602975D02*
G03X2644Y604724I-4948J-6125D01*
G01X7593Y602975D02*
G03X2644Y604724I-4948J-6125D01*
G01X7593Y602975D02*
G03X2644Y604724I-4948J-6125D01*
G01X7593Y602975D02*
G03X2644Y604724I-4948J-6125D01*
G01X7595Y602975D02*
G03X2646Y604724I-4948J-6125D01*
G01X2644Y616535D02*
G03X7593Y618285I0J7874D01*
G01X2644Y616535D02*
G03X7593Y618285I0J7874D01*
G01X2646Y616535D02*
G03X7595Y618285I0J7874D01*
G01Y602975D02*
G03Y618285I6186J7655D01*
G01X7593Y602975D02*
G03Y618285I6187J7655D01*
G01Y602975D02*
G03Y618285I6187J7655D01*
G01Y602975D02*
G03Y618285I6187J7655D01*
G01Y602975D02*
G03Y618285I6187J7655D01*
G01X7595Y602975D02*
G03Y618285I6186J7655D01*
G01X-7874Y626378D02*
G03Y634252I0J3937D01*
G01Y626378D02*
G03Y634252I0J3937D01*
G01X22835D02*
G03Y626378I0J-3937D01*
G01Y634252D02*
X137795D01*
G01X22835D02*
X137795D01*
G01X22835D02*
G03Y626378I0J-3937D01*
G01X168504Y-23622D02*
G03Y-31496I0J-3937D01*
G01X137795D02*
G03Y-23622I0J3937D01*
G01X341732Y-31496D02*
X168504D01*
G01X341732D02*
X168504D01*
G01X137795D02*
G03Y-23622I0J3937D01*
G01X168504D02*
G03Y-31496I0J-3937D01*
G01Y634252D02*
G03Y626378I0J-3937D01*
G01X137795D02*
G03Y634252I0J3937D01*
G01X168504D02*
X341732D01*
G01X168504D02*
X341732D01*
G01X137795Y626378D02*
G03Y634252I0J3937D01*
G01X168504D02*
G03Y626378I0J-3937D01*
G01X341732Y-31496D02*
G03Y-23622I0J3937D01*
G01Y-31496D02*
G03Y-23622I0J3937D01*
G01Y626378D02*
G03Y634252I0J3937D01*
G01Y626378D02*
G03Y634252I0J3937D01*
G01X372441Y-23622D02*
G03Y-31496I0J-3937D01*
G01X529921D02*
X372441D01*
G01X529921D02*
X372441D01*
G01Y-23622D02*
G03Y-31496I0J-3937D01*
G01Y634252D02*
G03Y626378I0J-3937D01*
G01Y634252D02*
X529921D01*
G01X372441D02*
X529921D01*
G01X372441D02*
G03Y626378I0J-3937D01*
G01X529921Y-31496D02*
G03Y-23622I0J3937D01*
G01Y-31496D02*
G03Y-23622I0J3937D01*
G01Y626378D02*
G03Y634252I0J3937D01*
G01Y626378D02*
G03Y634252I0J3937D01*
G01X560630Y-23622D02*
G03Y-31496I0J-3937D01*
G01X788976D02*
X560630D01*
G01X788976D02*
X560630D01*
G01Y-23622D02*
G03Y-31496I0J-3937D01*
G01Y634252D02*
G03Y626378I0J-3937D01*
G01Y634252D02*
X788976D01*
G01X560630D02*
X788976D01*
G01X560630D02*
G03Y626378I0J-3937D01*
G01X684760Y-15529D02*
G03Y-219I6187J7655D01*
G01X684759Y-15529D02*
G03X679809Y-13780I-4948J-6125D01*
G01X679811Y-1969D02*
G03X684760Y-219I0J7874D01*
G01X677165Y-1969D02*
X679811D01*
G01X677165D02*
G03Y-13780I0J-5906D01*
G01D02*
X679809D01*
G01X684760Y602975D02*
G03Y618285I6187J7655D01*
G01X684759Y602975D02*
G03Y618285I6186J7655D01*
G01Y602975D02*
G03Y618285I6186J7655D01*
G01Y602975D02*
G03Y618285I6186J7655D01*
G01Y602975D02*
G03Y618285I6186J7655D01*
G01X684760Y602975D02*
G03Y618285I6187J7655D01*
G01X679811Y616535D02*
G03X684760Y618285I0J7874D01*
G01X679809Y616535D02*
G03X684759Y618285I0J7874D01*
G01X679809Y616535D02*
G03X684759Y618285I0J7874D01*
G01X684760Y602975D02*
G03X679811Y604724I-4948J-6125D01*
G01X684759Y602975D02*
G03X679809Y604724I-4948J-6125D01*
G01X684759Y602975D02*
G03X679809Y604724I-4948J-6125D01*
G01X684759Y602975D02*
G03X679809Y604724I-4948J-6125D01*
G01X684759Y602975D02*
G03X679809Y604724I-4948J-6125D01*
G01X684760Y602975D02*
G03X679811Y604724I-4948J-6125D01*
G01X679809Y616535D02*
G03X684759Y618285I0J7874D01*
G01X679809Y616535D02*
G03X684759Y618285I0J7874D01*
G01X679811Y616535D02*
G03X684760Y618285I0J7874D01*
G01X677165Y616535D02*
X679811D01*
G01X677165D02*
G03Y604724I0J-5905D01*
G01D02*
X679809D01*
G01X788976Y-31496D02*
G03Y-23622I0J3937D01*
G01Y-31496D02*
G03Y-23622I0J3937D01*
G01X819685D02*
G03Y-31496I0J-3937D01*
G01X975591D02*
X819685D01*
G01X975591D02*
X819685D01*
G01Y-23622D02*
G03Y-31496I0J-3937D01*
G01X788976Y626378D02*
G03Y634252I0J3937D01*
G01Y626378D02*
G03Y634252I0J3937D01*
G01X819685D02*
G03Y626378I0J-3937D01*
G01Y634252D02*
X975591D01*
G01X819685D02*
X975591D01*
G01X819685D02*
G03Y626378I0J-3937D01*
G01X975591Y-31496D02*
G03Y-23622I0J3937D01*
G01Y-31496D02*
G03Y-23622I0J3937D01*
G01X1006299D02*
G03Y-31496I0J-3937D01*
G01X1162205D02*
X1006299D01*
G01X1162205D02*
X1006299D01*
G01Y-23622D02*
G03Y-31496I0J-3937D01*
G01Y634252D02*
X1162205D01*
G01X1006299D02*
X1162205D01*
G01X975591Y626378D02*
G03Y634252I0J3937D01*
G01Y626378D02*
G03Y634252I0J3937D01*
G01X1006299D02*
G03Y626378I0J-3937D01*
G01Y634252D02*
G03Y626378I0J-3937D01*
G01X1162205Y-31496D02*
G03Y-23622I0J3937D01*
G01Y-31496D02*
G03Y-23622I0J3937D01*
G01X1192913D02*
G03Y-31496I0J-3937D01*
G01X1398425D02*
X1192913D01*
G01X1398425D02*
X1192913D01*
G01Y-23622D02*
G03Y-31496I0J-3937D01*
G01Y634252D02*
X1394488D01*
G01X1192913D02*
X1394488D01*
G01X1162205Y626378D02*
G03Y634252I0J3937D01*
G01Y626378D02*
G03Y634252I0J3937D01*
G01X1192913D02*
G03Y626378I0J-3937D01*
G01Y634252D02*
G03Y626378I0J-3937D01*
G01X1398425Y-31496D02*
G03Y-23622I0J3937D01*
G01Y-31496D02*
G03Y-23622I0J3937D01*
G01X1405512Y-1968D02*
G03Y-13779I0J-5906D01*
G01Y-1968D02*
G03Y-13779I0J-5906D01*
G01Y-1968D02*
G03Y-13779I0J-5906D01*
G01Y-1968D02*
G03Y-13779I0J-5906D01*
G01X1394488Y626378D02*
G03Y634252I0J3937D01*
G01Y626378D02*
G03Y634252I0J3937D01*
G01X1405512Y616535D02*
G03Y604724I0J-5905D01*
G01Y616535D02*
G03Y604724I0J-5905D01*
G01Y616535D02*
G03Y604724I0J-5905D01*
G01Y616535D02*
G03Y604724I0J-5905D01*
G01X1429134Y-23622D02*
G03Y-31496I0J-3937D01*
G01X1851181D02*
X1429134D01*
G01X1851181D02*
X1429134D01*
G01Y-23622D02*
G03Y-31496I0J-3937D01*
G01X1413107Y-15529D02*
G03Y-218I6186J7655D01*
G01X1413105Y-15529D02*
G03Y-218I6186J7655D01*
G01Y-15529D02*
G03Y-218I6186J7655D01*
G01Y-15529D02*
G03Y-218I6186J7655D01*
G01Y-15529D02*
G03Y-218I6186J7655D01*
G01X1413107Y-15529D02*
G03Y-218I6186J7655D01*
G01X1408157Y-1968D02*
G03X1413107Y-218I1J7874D01*
G01X1408156Y-1968D02*
G03X1413105Y-218I0J7874D01*
G01X1408156Y-1968D02*
G03X1413105Y-218I0J7874D01*
G01X1408156Y-1968D02*
G03X1413105Y-218I0J7874D01*
G01X1408156Y-1968D02*
G03X1413105Y-218I0J7874D01*
G01X1408157Y-1968D02*
G03X1413107Y-218I1J7874D01*
G01Y-15529D02*
G03X1408157Y-13779I-4949J-6124D01*
G01X1413105Y-15529D02*
G03X1408156Y-13779I-4949J-6124D01*
G01X1413105Y-15529D02*
G03X1408156Y-13779I-4949J-6124D01*
G01X1413105Y-15529D02*
G03X1408156Y-13779I-4949J-6124D01*
G01X1413105Y-15529D02*
G03X1408156Y-13779I-4949J-6124D01*
G01X1413107Y-15529D02*
G03X1408157Y-13779I-4949J-6124D01*
G01X1405512D02*
X1408156D01*
G01X1408157D02*
X1405512D01*
G01X1408157D02*
X1405512D01*
G01D02*
X1408156D01*
G01X1405512Y-1968D02*
X1408157D01*
G01X1408156D02*
X1405512D01*
G01X1408156D02*
X1405512D01*
G01D02*
X1408157D01*
G01X1425197Y634252D02*
X1851181D01*
G01X1425197D02*
X1851181D01*
G01X1425197D02*
G03Y626378I0J-3937D01*
G01Y634252D02*
G03Y626378I0J-3937D01*
G01X1408157Y616535D02*
G03X1413107Y618285I1J7874D01*
G01X1408156Y616535D02*
G03X1413105Y618285I0J7874D01*
G01X1408156Y616535D02*
G03X1413105Y618285I0J7874D01*
G01X1413107Y602975D02*
G03Y618285I6186J7655D01*
G01X1413105Y602975D02*
G03Y618285I6187J7655D01*
G01Y602975D02*
G03Y618285I6187J7655D01*
G01X1413107Y602975D02*
G03X1408157Y604724I-4948J-6125D01*
G01X1413105Y602975D02*
G03X1408156Y604724I-4948J-6125D01*
G01X1413105Y602975D02*
G03X1408156Y604724I-4948J-6125D01*
G01X1413105Y602975D02*
G03X1408156Y604724I-4948J-6125D01*
G01X1413105Y602975D02*
G03X1408156Y604724I-4948J-6125D01*
G01X1413107Y602975D02*
G03X1408157Y604724I-4948J-6125D01*
G01X1413105Y602975D02*
G03Y618285I6187J7655D01*
G01Y602975D02*
G03Y618285I6187J7655D01*
G01X1413107Y602975D02*
G03Y618285I6186J7655D01*
G01X1408156Y616535D02*
G03X1413105Y618285I0J7874D01*
G01X1408156Y616535D02*
G03X1413105Y618285I0J7874D01*
G01X1408157Y616535D02*
G03X1413107Y618285I1J7874D01*
G01X1405512Y616535D02*
X1408157D01*
G01X1408156D02*
X1405512D01*
G01Y604724D02*
X1408156D01*
G01X1408157D02*
X1405512D01*
G01X1408157D02*
X1405512D01*
G01D02*
X1408156D01*
G01Y616535D02*
X1405512D01*
G01D02*
X1408157D01*
G01X1685866Y267244D02*
X1883780D01*
G01X1685866D02*
X1883780D01*
G01X1685866D02*
X1883780D01*
G01X1685866D02*
X1883780D01*
G01X1681929Y271181D02*
G03X1685866Y267244I3937J0D01*
G01X1681929Y271181D02*
G03X1685866Y267244I3937J0D01*
G01X1681929Y271181D02*
G03X1685866Y267244I3937J0D01*
G01X1681929Y271181D02*
G03X1685866Y267244I3937J0D01*
G01X1681929Y428661D02*
Y271181D01*
G01Y428661D02*
Y271181D01*
G01Y428661D02*
Y271181D01*
G01Y428661D02*
Y271181D01*
G01X1685866Y432598D02*
G03X1681929Y428661I0J-3937D01*
G01X1685866Y432598D02*
G03X1681929Y428661I0J-3937D01*
G01X1972441Y432598D02*
X1685866D01*
G01X1972441D02*
X1685866D01*
G01X1972441D02*
X1685866D01*
G01X1972441D02*
X1685866D01*
G01D02*
G03X1681929Y428661I0J-3937D01*
G01X1685866Y432598D02*
G03X1681929Y428661I0J-3937D01*
G01X1851181Y-31496D02*
G03Y-23622I0J3937D01*
G01Y-31496D02*
G03Y-23622I0J3937D01*
G01X1881890D02*
G03Y-31496I0J-3937D01*
G01X1972441D02*
X1881890D01*
G01X1972441D02*
X1881890D01*
G01Y-23622D02*
G03Y-31496I0J-3937D01*
G01X1861926Y-15529D02*
G03X1856976Y-13780I-4948J-6125D01*
G01X1861924Y-15529D02*
G03X1856975Y-13780I-4948J-6125D01*
G01X1861924Y-15529D02*
G03X1856975Y-13780I-4948J-6125D01*
G01X1861924Y-15529D02*
G03X1856975Y-13780I-4948J-6125D01*
G01X1861924Y-15529D02*
G03X1856975Y-13780I-4948J-6125D01*
G01X1861926Y-15529D02*
G03X1856976Y-13780I-4948J-6125D01*
G01Y-1969D02*
G03X1861926Y-219I0J7874D01*
G01X1856975Y-1969D02*
G03X1861924Y-219I0J7874D01*
G01X1856975Y-1969D02*
G03X1861924Y-219I0J7874D01*
G01X1861926Y-15529D02*
G03Y-219I6186J7655D01*
G01X1861924Y-15529D02*
G03Y-219I6186J7655D01*
G01Y-15529D02*
G03Y-219I6186J7655D01*
G01Y-15529D02*
G03Y-219I6186J7655D01*
G01Y-15529D02*
G03Y-219I6186J7655D01*
G01X1861926Y-15529D02*
G03Y-219I6186J7655D01*
G01X1856975Y-1969D02*
G03X1861924Y-219I0J7874D01*
G01X1856975Y-1969D02*
G03X1861924Y-219I0J7874D01*
G01X1856976Y-1969D02*
G03X1861926Y-219I0J7874D01*
G01X1854331Y-1969D02*
G03Y-13780I0J-5906D01*
G01Y-1969D02*
G03Y-13780I0J-5906D01*
G01D02*
X1856975D01*
G01X1856976D02*
X1854331D01*
G01X1856976D02*
X1854331D01*
G01D02*
X1856975D01*
G01X1854331Y-1969D02*
G03Y-13780I0J-5906D01*
G01Y-1969D02*
G03Y-13780I0J-5906D01*
G01Y-1969D02*
X1856976D01*
G01X1856975D02*
X1854331D01*
G01X1856975D02*
X1854331D01*
G01D02*
X1856976D01*
G01X1891654Y246772D02*
X1972441D01*
G01X1891654D02*
X1972441D01*
G01X1891654D02*
X1972441D01*
G01X1891654D02*
X1972441D01*
G01X1887717Y250709D02*
G03X1891654Y246772I3937J0D01*
G01X1887717Y250709D02*
G03X1891654Y246772I3937J0D01*
G01X1887717Y263307D02*
Y250709D01*
G01Y263307D02*
Y250709D01*
G01Y263307D02*
Y250709D01*
G01Y263307D02*
Y250709D01*
G01D02*
G03X1891654Y246772I3937J0D01*
G01X1887717Y250709D02*
G03X1891654Y246772I3937J0D01*
G01X1887717Y263307D02*
G03X1883780Y267244I-3937J0D01*
G01X1887717Y263307D02*
G03X1883780Y267244I-3937J0D01*
G01X1887717Y263307D02*
G03X1883780Y267244I-3937J0D01*
G01X1887717Y263307D02*
G03X1883780Y267244I-3937J0D01*
G01X1881890Y634252D02*
G03Y626378I0J-3937D01*
G01Y634252D02*
X1972441D01*
G01X1881890D02*
X1972441D01*
G01X1881890D02*
G03Y626378I0J-3937D01*
G01X1851181D02*
G03Y634252I0J3937D01*
G01Y626378D02*
G03Y634252I0J3937D01*
G01X1856976Y616535D02*
G03X1861926Y618285I0J7874D01*
G01X1856975Y616535D02*
G03X1861924Y618285I0J7874D01*
G01X1856975Y616535D02*
G03X1861924Y618285I0J7874D01*
G01X1861926Y602975D02*
G03Y618285I6186J7655D01*
G01X1861924Y602975D02*
G03Y618285I6186J7655D01*
G01Y602975D02*
G03Y618285I6186J7655D01*
G01Y602975D02*
G03Y618285I6186J7655D01*
G01Y602975D02*
G03Y618285I6186J7655D01*
G01X1861926Y602975D02*
G03Y618285I6186J7655D01*
G01X1856975Y616535D02*
G03X1861924Y618285I0J7874D01*
G01X1856975Y616535D02*
G03X1861924Y618285I0J7874D01*
G01X1856976Y616535D02*
G03X1861926Y618285I0J7874D01*
G01Y602975D02*
G03X1856976Y604724I-4948J-6125D01*
G01X1861924Y602975D02*
G03X1856975Y604724I-4948J-6125D01*
G01X1861924Y602975D02*
G03X1856975Y604724I-4948J-6125D01*
G01X1861924Y602975D02*
G03X1856975Y604724I-4948J-6125D01*
G01X1861924Y602975D02*
G03X1856975Y604724I-4948J-6125D01*
G01X1861926Y602975D02*
G03X1856976Y604724I-4948J-6125D01*
G01X1854331Y616535D02*
G03Y604724I0J-5905D01*
G01Y616535D02*
G03Y604724I0J-5905D01*
G01D02*
X1856975D01*
G01X1856976D02*
X1854331D01*
G01X1856976D02*
X1854331D01*
G01D02*
X1856975D01*
G01X1854331Y616535D02*
G03Y604724I0J-5905D01*
G01Y616535D02*
G03Y604724I0J-5905D01*
G01Y616535D02*
X1856976D01*
G01X1856975D02*
X1854331D01*
G01X1856975D02*
X1854331D01*
G01D02*
X1856976D01*
G01X1972441Y-11811D02*
X1906890D01*
G01X1904921Y-9843D02*
G03X1906890Y-11811I1969J1D01*
G01X1904921Y53150D02*
Y-9843D01*
G01X1972441Y-11811D02*
X1906890D01*
G01X1904921Y-9843D02*
G03X1906890Y-11811I1969J1D01*
G01X1904921Y53150D02*
Y-9843D01*
G01X1923071Y53150D02*
Y-9843D01*
G01X1940787Y-3937D02*
X1972441D01*
G01X1940787D02*
G03X1938819Y-5906I0J-1968D01*
G01Y-9843D02*
Y-5906D01*
G01Y-9843D02*
G03X1940787Y-11811I1968J0D01*
G01X1921102D02*
G03X1923071Y-9843I0J1969D01*
G01X1906890Y55118D02*
G03X1904921Y53150I0J-1969D01*
G01X1972441Y55118D02*
X1906890D01*
G01X1972441D02*
X1906890D01*
G01X1972441D02*
X1906890D01*
G01X1972441D02*
X1906890D01*
G01D02*
G03X1904921Y53150I0J-1969D01*
G01X1923071D02*
G03X1921102Y55118I-1969J-1D01*
G01X1940787D02*
G03X1938819Y53150I0J-1968D01*
G01Y49213D02*
Y53150D01*
G01Y49213D02*
G03X1940787Y47244I1968J-1D01*
G01X1972441D02*
X1940787D01*
G01X1976378Y-35433D02*
G03X1972441Y-31496I-3937J0D01*
G01X1976378Y-59055D02*
Y-35433D01*
G01Y-59055D02*
Y-35433D01*
G01D02*
G03X1972441Y-31496I-3937J0D01*
G01Y-62992D02*
G03X1976378Y-59055I0J3937D01*
G01X1972441Y-62992D02*
G03X1976378Y-59055I0J3937D01*
G01X1972441Y-23622D02*
G03X1976378Y-19685I0J3937D01*
G01X1972441Y-23622D02*
G03X1976378Y-19685I0J3937D01*
G01X1972441Y-23622D02*
G03X1976378Y-19685I0J3937D01*
G01X1972441Y-23622D02*
G03X1976378Y-19685I0J3937D01*
G01D02*
Y-15748D01*
G01Y-19685D02*
Y-15748D01*
G01Y-19685D02*
Y-15748D01*
G01Y-19685D02*
Y-15748D01*
G01D02*
G03X1972441Y-11811I-3937J0D01*
G01X1976378Y-15748D02*
G03X1972441Y-11811I-3937J0D01*
G01X1976378Y-15748D02*
G03X1972441Y-11811I-3937J0D01*
G01X1976378Y-15748D02*
G03X1972441Y-11811I-3937J0D01*
G01X1976378Y0D02*
Y43307D01*
G01X1972441Y-3937D02*
G03X1976378Y0I0J3937D01*
G01X1972441Y55118D02*
G03X1976378Y59055I0J3937D01*
G01X1972441Y55118D02*
G03X1976378Y59055I0J3937D01*
G01X1972441Y55118D02*
G03X1976378Y59055I0J3937D01*
G01X1972441Y55118D02*
G03X1976378Y59055I0J3937D01*
G01D02*
Y242835D01*
G01Y59055D02*
Y242835D01*
G01Y59055D02*
Y242835D01*
G01Y59055D02*
Y242835D01*
G01Y43307D02*
G03X1972441Y47244I-3937J0D01*
G01X1976378Y242835D02*
G03X1972441Y246772I-3937J0D01*
G01X1976378Y242835D02*
G03X1972441Y246772I-3937J0D01*
G01X1976378Y242835D02*
G03X1972441Y246772I-3937J0D01*
G01X1976378Y242835D02*
G03X1972441Y246772I-3937J0D01*
G01Y432598D02*
G03X1976378Y436535I0J3937D01*
G01X1972441Y432598D02*
G03X1976378Y436535I0J3937D01*
G01X1972441Y432598D02*
G03X1976378Y436535I0J3937D01*
G01X1972441Y432598D02*
G03X1976378Y436535I0J3937D01*
G01D02*
Y622441D01*
G01Y436535D02*
Y622441D01*
G01Y436535D02*
Y622441D01*
G01Y436535D02*
Y622441D01*
G01D02*
G03X1972441Y626378I-3937J0D01*
G01X1976378Y622441D02*
G03X1972441Y626378I-3937J0D01*
G01X1976378Y622441D02*
G03X1972441Y626378I-3937J0D01*
G01X1976378Y622441D02*
G03X1972441Y626378I-3937J0D01*
G01Y634252D02*
G03X1976378Y638189I0J3937D01*
G01X1972441Y634252D02*
G03X1976378Y638189I0J3937D01*
G01D02*
Y661811D01*
G01Y638189D02*
Y661811D01*
G01D02*
G03X1972441Y665748I-3937J0D01*
G01X1976378Y661811D02*
G03X1972441Y665748I-3937J0D01*
G54D152*
X1274699Y333959D03*
G54D143*
X1261972Y300150D03*
X1245219Y322557D03*
X1260848Y293146D03*
G54D215*
X1487858Y608784D03*
X1523396Y610052D03*
G54D233*
X1595602Y3337D03*
Y1369D03*
Y-600D03*
Y-2569D03*
Y-4537D03*
G54D260*
X1743680Y505270D03*
Y515070D03*
G54D161*
X1239184Y461227D03*
X1254389Y470270D03*
G54D170*
X1281987Y215066D03*
G54D41*
X2940Y41740D03*
Y47240D03*
X116124Y112393D03*
Y106893D03*
X194600Y242848D03*
Y248348D03*
Y238348D03*
Y232848D03*
Y274000D03*
Y279500D03*
Y303000D03*
Y308500D03*
Y335730D03*
Y341230D03*
Y363600D03*
Y369100D03*
X411989Y274654D03*
Y269154D03*
X416889Y274654D03*
Y269154D03*
X407089Y274654D03*
Y269154D03*
X402148Y274841D03*
Y269341D03*
X397256Y274841D03*
Y269341D03*
X411060Y300154D03*
Y305654D03*
X415960Y300154D03*
Y305654D03*
X410860Y283000D03*
Y288500D03*
X415860Y283000D03*
Y288500D03*
X406160Y300154D03*
Y305654D03*
Y283154D03*
Y288654D03*
X416192Y318900D03*
Y313400D03*
X412407Y328713D03*
Y334213D03*
X417307Y328713D03*
Y334213D03*
X407507Y328713D03*
Y334213D03*
X406192Y318900D03*
Y313400D03*
X367360Y315654D03*
Y321154D03*
X372060Y315654D03*
Y321154D03*
X376760Y315654D03*
Y321154D03*
X382413Y324585D03*
Y330085D03*
X387892Y328000D03*
Y333500D03*
X402592Y328200D03*
Y333700D03*
X397692Y328200D03*
Y333700D03*
X392792Y328200D03*
Y333700D03*
X391492Y318900D03*
Y313400D03*
X386592Y318900D03*
Y313400D03*
X401292Y318900D03*
Y313400D03*
X396392Y318900D03*
Y313400D03*
X381692Y318900D03*
Y313400D03*
X391460Y300154D03*
Y305654D03*
X386560Y283154D03*
Y288654D03*
X376760Y300154D03*
Y305654D03*
X381660Y300154D03*
Y305654D03*
X366960Y300154D03*
Y305654D03*
X371860Y300154D03*
Y305654D03*
X381660Y283154D03*
Y288654D03*
X371860Y283154D03*
Y288654D03*
X366960Y283154D03*
Y288654D03*
X376760Y283154D03*
Y288654D03*
X386560Y300154D03*
Y305654D03*
X396360Y300154D03*
Y305654D03*
Y283154D03*
Y288654D03*
X401260Y300154D03*
Y305654D03*
Y283154D03*
Y288654D03*
X391460Y283154D03*
Y288654D03*
X411192Y318900D03*
Y313400D03*
X421789Y274654D03*
Y269154D03*
X446563Y299154D03*
Y304654D03*
X448298Y287841D03*
Y282341D03*
X420860Y300154D03*
Y305654D03*
Y283000D03*
Y288500D03*
X440860Y283154D03*
Y288654D03*
X430860Y283154D03*
Y288654D03*
X435860Y283154D03*
Y288654D03*
X426648Y299341D03*
Y304841D03*
X425860Y283154D03*
Y288654D03*
X451463Y299154D03*
Y304654D03*
X436648Y299341D03*
Y304841D03*
X453298Y287841D03*
Y282341D03*
X431648Y299341D03*
Y304841D03*
X441663Y299154D03*
Y304654D03*
X426192Y318900D03*
Y313400D03*
X451192Y318900D03*
Y313400D03*
X436192Y318900D03*
Y313400D03*
X431192Y318900D03*
Y313400D03*
X441192Y318900D03*
Y313400D03*
X446192Y318900D03*
Y313400D03*
X427115Y328713D03*
Y334213D03*
X422207Y328713D03*
Y334213D03*
X458148Y314841D03*
Y320341D03*
X421192Y318900D03*
Y313400D03*
X637000Y244000D03*
Y249500D03*
Y239000D03*
Y233500D03*
X665550Y516300D03*
Y521800D03*
X719100Y572000D03*
Y577500D03*
X824000Y196792D03*
Y202292D03*
X844500Y238480D03*
Y232980D03*
Y242980D03*
Y248480D03*
Y271500D03*
Y277000D03*
Y303200D03*
Y308700D03*
Y334750D03*
Y340250D03*
X845900Y366300D03*
Y371800D03*
X1031268Y300154D03*
Y305654D03*
Y283154D03*
Y288654D03*
X1021468Y315654D03*
Y321154D03*
X1026368Y315654D03*
Y321154D03*
X1016568Y315604D03*
Y321104D03*
X1031300Y318900D03*
Y313400D03*
X1032021Y324585D03*
Y330085D03*
X1021468Y283154D03*
Y288654D03*
X1016568Y300154D03*
Y305654D03*
Y283154D03*
Y288654D03*
X1026368Y300154D03*
Y305654D03*
X1021468Y300154D03*
Y305654D03*
X1026368Y283154D03*
Y288654D03*
X1061597Y274654D03*
Y269154D03*
X1071397Y274654D03*
Y269154D03*
X1066497Y274654D03*
Y269154D03*
X1056697Y274654D03*
Y269154D03*
X1051756Y274841D03*
Y269341D03*
X1046856Y274841D03*
Y269341D03*
X1091271Y299154D03*
Y304654D03*
X1096171Y299154D03*
Y304654D03*
X1090468Y283154D03*
Y288654D03*
X1081256Y299341D03*
Y304841D03*
X1086256Y299341D03*
Y304841D03*
X1085468Y283154D03*
Y288654D03*
X1080468Y283154D03*
Y288654D03*
X1076256Y299341D03*
Y304841D03*
X1075468Y283154D03*
Y288654D03*
X1075800Y318900D03*
Y313400D03*
X1080800Y318900D03*
Y313400D03*
X1085800Y318900D03*
Y313400D03*
X1095800Y318900D03*
Y313400D03*
X1090800Y318900D03*
Y313400D03*
X1080445Y328343D03*
Y333843D03*
X1065800Y318900D03*
Y313400D03*
X1046000Y318900D03*
Y313400D03*
X1041100Y318900D03*
Y313400D03*
X1036200Y318900D03*
Y313400D03*
X1055800Y318900D03*
Y313400D03*
X1050900Y318900D03*
Y313400D03*
X1062015Y328713D03*
Y334213D03*
X1066915Y328713D03*
Y334213D03*
X1071815Y328713D03*
Y334213D03*
X1052200Y328200D03*
Y333700D03*
X1057115Y328713D03*
Y334213D03*
X1047300Y328200D03*
Y333700D03*
X1037500Y328000D03*
Y333500D03*
X1042400Y328200D03*
Y333700D03*
X1070468Y283000D03*
Y288500D03*
X1065568Y300154D03*
Y305654D03*
X1065468Y283000D03*
Y288500D03*
X1070468Y300154D03*
Y305654D03*
X1045968Y300154D03*
Y305654D03*
Y283154D03*
Y288654D03*
X1041068Y300154D03*
Y305654D03*
Y283154D03*
Y288654D03*
X1036168Y300154D03*
Y305654D03*
Y283154D03*
Y288654D03*
X1060668Y300154D03*
Y305654D03*
X1050868Y300154D03*
Y305654D03*
X1055768Y300154D03*
Y305654D03*
X1060468Y283000D03*
Y288500D03*
X1055768Y283154D03*
Y288654D03*
X1050868Y283154D03*
Y288654D03*
X1060800Y318900D03*
Y313400D03*
X1070800Y318900D03*
Y313400D03*
X1101071Y299154D03*
Y304654D03*
X1102906Y287841D03*
Y282341D03*
X1097906Y287841D03*
Y282341D03*
X1100800Y318900D03*
Y313400D03*
X1109356Y313150D03*
Y318650D03*
X1341634Y100694D03*
Y106194D03*
X1335664Y514096D03*
Y519596D03*
X1320049Y504266D03*
Y509766D03*
X1383506Y22417D03*
Y16917D03*
X1453900Y385100D03*
Y390600D03*
X1455600Y422100D03*
Y427600D03*
X1464600Y524200D03*
Y518700D03*
X1455600Y519000D03*
Y513500D03*
X1450400Y519000D03*
Y513500D03*
X1469600Y524200D03*
Y518700D03*
X1478500Y525500D03*
Y520000D03*
X1487450Y534300D03*
Y539800D03*
X1579700Y517900D03*
Y512400D03*
X1589100Y499750D03*
Y505250D03*
X1574700Y517900D03*
Y512400D03*
X1584000Y606000D03*
Y600500D03*
X1611630Y74134D03*
Y79134D03*
X1607000Y491500D03*
Y497000D03*
X1612000Y491500D03*
Y497000D03*
X1594300Y499750D03*
Y505250D03*
X1599500Y499750D03*
Y505250D03*
X1832000Y157000D03*
Y162500D03*
X1847650Y104640D03*
Y99140D03*
G54D116*
X724937Y-652D03*
X722968D03*
X721000D03*
X719031D03*
X717063D03*
Y10652D03*
X719031D03*
X721000D03*
X722968D03*
X724937D03*
X723980Y584050D03*
X722012D03*
X720043D03*
X718075D03*
X716106D03*
Y595354D03*
X718075D03*
X720043D03*
X722012D03*
X723980D03*
X1587610Y582396D03*
X1585641D03*
X1583673D03*
X1581704D03*
Y593700D03*
X1583673D03*
X1585641D03*
X1587610D03*
X1589578Y582396D03*
Y593700D03*
X1850700Y150348D03*
X1848732D03*
X1846763D03*
X1854637D03*
X1852669D03*
X1848732Y161652D03*
X1850700D03*
X1852669D03*
X1846763D03*
X1854637D03*
G54D14*
X-14722Y452578D03*
X-5722D03*
X97600Y167800D03*
X88600D03*
X83820Y478080D03*
X74820D03*
X85865Y470975D03*
X76865D03*
X1683500Y82500D03*
X1692500D03*
X1883000Y554600D03*
X1890400D03*
X1883000Y557160D03*
X1890400D03*
X1883000Y552040D03*
X1890400D03*
G54D251*
X1710594Y516950D03*
Y508850D03*
X1708626Y516950D03*
Y508850D03*
X1714530Y516950D03*
Y508850D03*
X1712562Y516950D03*
Y508850D03*
G54D50*
X35499Y431705D03*
X28499D03*
X28871Y441432D03*
X35871D03*
X28871Y448191D03*
X35871D03*
X47500Y562500D03*
X47150Y599650D03*
X68572Y18008D03*
X75572D03*
X68671Y10407D03*
X75671D03*
X61000Y216212D03*
X54000D03*
X104733Y514100D03*
Y589700D03*
Y551900D03*
X54500Y562500D03*
X54150Y599650D03*
X111733Y514100D03*
Y589700D03*
Y551900D03*
X378292Y13078D03*
X371292D03*
X378432Y51198D03*
X371432D03*
X378292Y589678D03*
X371292D03*
X378842Y551578D03*
X371842D03*
X647900Y286000D03*
X640900D03*
X718437Y-10548D03*
X725437D03*
X721131Y42955D03*
X721000Y520500D03*
X722606Y605050D03*
X715606D03*
X715370Y613530D03*
X722370D03*
X728131Y42955D03*
X753000Y512000D03*
X760000D03*
X728000Y520500D03*
X753343Y551878D03*
X760343D03*
X753343Y589678D03*
X760343D03*
X1028400Y13078D03*
X1021400D03*
X1028630Y51028D03*
X1021630D03*
X1028200Y551000D03*
X1021200D03*
X1027100Y589700D03*
X1020100D03*
X1338000Y46000D03*
X1331000D03*
X1508750Y547150D03*
X1501750D03*
X1559983Y567937D03*
X1552983D03*
X1585270Y558204D03*
Y565204D03*
X1592270Y558204D03*
Y565204D03*
X1691342Y495833D03*
X1698342D03*
X1771500Y516700D03*
X1785000Y100100D03*
X1778000D03*
X1796848Y160937D03*
X1803848D03*
X1778500Y516700D03*
X1837463Y144198D03*
X1844463D03*
X1955046Y76272D03*
X1955458Y88011D03*
X1962046Y76272D03*
X1962458Y88011D03*
G54D32*
X24047Y37443D03*
X24372Y68810D03*
X13947Y544099D03*
Y580099D03*
X138071Y224632D03*
Y288632D03*
Y256632D03*
Y320632D03*
Y352632D03*
Y384632D03*
X787679Y224632D03*
Y256632D03*
Y288632D03*
Y320632D03*
Y352632D03*
X787629Y384632D03*
G54D134*
X721319Y492850D03*
X1394664Y540952D03*
X1541300Y313400D03*
X1634350Y201350D03*
X1736689Y169831D03*
X1732189D03*
X1727689D03*
X1723189D03*
Y162331D03*
X1727689D03*
X1732189D03*
X1736689D03*
X1718689D03*
Y169781D03*
X1714189Y162331D03*
X1855663Y142248D03*
G54D23*
X25064Y-11490D03*
X6261Y485075D03*
X-1296Y485081D03*
X1351416Y43361D03*
G54D305*
X1952756Y558464D03*
G54D206*
X1475098Y374668D03*
Y377868D03*
X1478298Y371487D03*
X1481479Y368287D03*
X1484679D03*
X1475098Y487132D03*
Y490332D03*
Y493532D03*
X1478279Y496713D03*
X1481479D03*
X1484679D03*
X1478298Y493513D03*
X1579902Y377868D03*
Y374668D03*
Y371468D03*
X1576721Y368287D03*
X1573521D03*
X1570321D03*
X1576702Y371487D03*
X1579902Y490332D03*
Y487132D03*
X1570321Y496713D03*
X1573521D03*
X1576702Y493513D03*
X1576721Y496713D03*
X1579902Y493532D03*
G54D224*
X1570023Y104172D03*
X1611500Y401437D03*
X1731124Y583524D03*
X1729700Y564500D03*
G54D107*
X663091Y147445D03*
X658091D03*
X653091D03*
X648091D03*
X663091Y152445D03*
X658091D03*
X653091D03*
X648091D03*
X663091Y157445D03*
X658091D03*
X653091D03*
X648091D03*
X663091Y162445D03*
X658091D03*
X653091D03*
X648091D03*
X663091Y167445D03*
X658091D03*
X653091D03*
X648091D03*
X663091Y172445D03*
X658091D03*
X653091D03*
X648091D03*
X663091Y429925D03*
X658091D03*
X653091D03*
X648091D03*
X663091Y434925D03*
X658091D03*
X653091D03*
X648091D03*
X663091Y439925D03*
X658091D03*
X653091D03*
X648091D03*
X663091Y444925D03*
X658091D03*
X653091D03*
X648091D03*
X663091Y449925D03*
X658091D03*
X653091D03*
X648091D03*
X663091Y454925D03*
X658091D03*
X653091D03*
X648091D03*
X688091Y147445D03*
X683091D03*
X678091D03*
X673091D03*
X668091D03*
X723091D03*
X718091D03*
X713091D03*
X708091D03*
X703091D03*
X698091D03*
X693091D03*
X688091Y152445D03*
X683091D03*
X678091D03*
X673091D03*
X668091D03*
X723091D03*
X718091D03*
X713091D03*
X708091D03*
X703091D03*
X698091D03*
X693091D03*
X688091Y157445D03*
X683091D03*
X678091D03*
X673091D03*
X668091D03*
X723091D03*
X718091D03*
X713091D03*
X708091D03*
X703091D03*
X698091D03*
X693091D03*
X688091Y162445D03*
X683091D03*
X678091D03*
X673091D03*
X668091D03*
X723091D03*
X718091D03*
X713091D03*
X708091D03*
X703091D03*
X698091D03*
X693091D03*
X688091Y167445D03*
X683091D03*
X678091D03*
X673091D03*
X668091D03*
X723091D03*
X718091D03*
X713091D03*
X708091D03*
X703091D03*
X698091D03*
X693091D03*
X688091Y172445D03*
X683091D03*
X678091D03*
X673091D03*
X668091D03*
X723091D03*
X718091D03*
X713091D03*
X708091D03*
X703091D03*
X698091D03*
X693091D03*
X688091Y429925D03*
X683091D03*
X678091D03*
X673091D03*
X668091D03*
X723091D03*
X718091D03*
X713091D03*
X708091D03*
X703091D03*
X698091D03*
X693091D03*
X688091Y434925D03*
X683091D03*
X678091D03*
X673091D03*
X668091D03*
X723091D03*
X718091D03*
X713091D03*
X708091D03*
X703091D03*
X698091D03*
X693091D03*
X688091Y439925D03*
X683091D03*
X678091D03*
X673091D03*
X668091D03*
X723091D03*
X718091D03*
X713091D03*
X708091D03*
X703091D03*
X698091D03*
X693091D03*
X688091Y444925D03*
X683091D03*
X678091D03*
X673091D03*
X668091D03*
X723091D03*
X718091D03*
X713091D03*
X708091D03*
X703091D03*
X698091D03*
X693091D03*
X688091Y449925D03*
X683091D03*
X678091D03*
X673091D03*
X668091D03*
X723091D03*
X718091D03*
X713091D03*
X708091D03*
X703091D03*
X698091D03*
X693091D03*
X688091Y454925D03*
X683091D03*
X678091D03*
X673091D03*
X668091D03*
X723091D03*
X718091D03*
X713091D03*
X708091D03*
X703091D03*
X698091D03*
X693091D03*
X743091Y147445D03*
X738091D03*
X733091D03*
X728091D03*
X743091Y152445D03*
X738091D03*
X733091D03*
X728091D03*
X743091Y157445D03*
X738091D03*
X733091D03*
X728091D03*
X743091Y162445D03*
X738091D03*
X733091D03*
X728091D03*
X743091Y167445D03*
X738091D03*
X733091D03*
X728091D03*
X743091Y172445D03*
X738091D03*
X733091D03*
X728091D03*
X743091Y429925D03*
X738091D03*
X733091D03*
X728091D03*
X743091Y434925D03*
X738091D03*
X733091D03*
X728091D03*
X743091Y439925D03*
X738091D03*
X733091D03*
X728091D03*
X743091Y444925D03*
X738091D03*
X733091D03*
X728091D03*
X743091Y449925D03*
X738091D03*
X733091D03*
X728091D03*
X743091Y454925D03*
X738091D03*
X733091D03*
X728091D03*
X1337618Y147445D03*
X1332618D03*
X1327618D03*
X1322618D03*
X1317618D03*
X1312618D03*
X1307618D03*
X1302618D03*
X1342618D03*
X1297618D03*
X1337618Y152445D03*
X1332618D03*
X1327618D03*
X1322618D03*
X1317618D03*
X1312618D03*
X1307618D03*
X1302618D03*
X1342618D03*
X1297618D03*
X1337618Y157445D03*
X1332618D03*
X1327618D03*
X1322618D03*
X1317618D03*
X1312618D03*
X1307618D03*
X1302618D03*
X1342618D03*
X1297618D03*
X1337618Y162445D03*
X1332618D03*
X1327618D03*
X1322618D03*
X1317618D03*
X1312618D03*
X1307618D03*
X1302618D03*
X1342618D03*
X1297618D03*
X1337618Y167445D03*
X1332618D03*
X1327618D03*
X1322618D03*
X1317618D03*
X1312618D03*
X1307618D03*
X1302618D03*
X1342618D03*
X1297618D03*
X1337618Y172445D03*
X1332618D03*
X1327618D03*
X1322618D03*
X1317618D03*
X1312618D03*
X1307618D03*
X1302618D03*
X1342618D03*
X1297618D03*
X1337618Y429925D03*
X1332618D03*
X1327618D03*
X1322618D03*
X1317618D03*
X1312618D03*
X1307618D03*
X1302618D03*
X1342618D03*
X1297618D03*
X1337618Y434925D03*
X1332618D03*
X1327618D03*
X1322618D03*
X1317618D03*
X1312618D03*
X1307618D03*
X1302618D03*
X1342618D03*
X1297618D03*
X1337618Y439925D03*
X1332618D03*
X1327618D03*
X1322618D03*
X1317618D03*
X1312618D03*
X1307618D03*
X1302618D03*
X1342618D03*
X1297618D03*
X1337618Y444925D03*
X1332618D03*
X1327618D03*
X1322618D03*
X1317618D03*
X1312618D03*
X1307618D03*
X1302618D03*
X1342618D03*
X1297618D03*
X1337618Y449925D03*
X1332618D03*
X1327618D03*
X1322618D03*
X1317618D03*
X1312618D03*
X1307618D03*
X1302618D03*
X1342618D03*
X1297618D03*
X1337618Y454925D03*
X1332618D03*
X1327618D03*
X1322618D03*
X1317618D03*
X1312618D03*
X1307618D03*
X1302618D03*
X1342618D03*
X1297618D03*
X1392618Y147445D03*
X1387618D03*
X1382618D03*
X1377618D03*
X1372618D03*
X1367618D03*
X1362618D03*
X1357618D03*
X1352618D03*
X1347618D03*
X1392618Y152445D03*
X1387618D03*
X1382618D03*
X1377618D03*
X1372618D03*
X1367618D03*
X1362618D03*
X1357618D03*
X1352618D03*
X1347618D03*
X1392618Y157445D03*
X1387618D03*
X1382618D03*
X1377618D03*
X1372618D03*
X1367618D03*
X1362618D03*
X1357618D03*
X1352618D03*
X1347618D03*
X1392618Y162445D03*
X1387618D03*
X1382618D03*
X1377618D03*
X1372618D03*
X1367618D03*
X1362618D03*
X1357618D03*
X1352618D03*
X1347618D03*
X1392618Y167445D03*
X1387618D03*
X1382618D03*
X1377618D03*
X1372618D03*
X1367618D03*
X1362618D03*
X1357618D03*
X1352618D03*
X1347618D03*
X1392618Y172445D03*
X1387618D03*
X1382618D03*
X1377618D03*
X1372618D03*
X1367618D03*
X1362618D03*
X1357618D03*
X1352618D03*
X1347618D03*
X1392618Y429925D03*
X1387618D03*
X1382618D03*
X1377618D03*
X1372618D03*
X1367618D03*
X1362618D03*
X1357618D03*
X1352618D03*
X1347618D03*
X1392618Y434925D03*
X1387618D03*
X1382618D03*
X1377618D03*
X1372618D03*
X1367618D03*
X1362618D03*
X1357618D03*
X1352618D03*
X1347618D03*
X1392618Y439925D03*
X1387618D03*
X1382618D03*
X1377618D03*
X1372618D03*
X1367618D03*
X1362618D03*
X1357618D03*
X1352618D03*
X1347618D03*
X1392618Y444925D03*
X1387618D03*
X1382618D03*
X1377618D03*
X1372618D03*
X1367618D03*
X1362618D03*
X1357618D03*
X1352618D03*
X1347618D03*
X1392618Y449925D03*
X1387618D03*
X1382618D03*
X1377618D03*
X1372618D03*
X1367618D03*
X1362618D03*
X1357618D03*
X1352618D03*
X1347618D03*
X1392618Y454925D03*
X1387618D03*
X1382618D03*
X1377618D03*
X1372618D03*
X1367618D03*
X1362618D03*
X1357618D03*
X1352618D03*
X1347618D03*
G54D242*
X1602520Y425800D03*
X1597400Y424761D03*
G54D125*
X694053Y213901D03*
X1359142Y-6923D03*
X1359453Y25101D03*
X1361760Y383969D03*
X1363453Y571957D03*
Y603157D03*
G54D270*
X1840675Y94600D03*
X1842250D03*
X1843825D03*
G54D144*
X1265720Y287844D03*
G54D234*
X1632000Y47500D03*
Y64500D03*
G54D153*
X1268614Y341717D03*
G54D216*
X1478330Y608784D03*
X1513868Y610052D03*
G54D225*
X1569492Y125722D03*
X1692272Y119372D03*
X1682615Y113935D03*
G54D42*
X23900Y87700D03*
X16300D03*
X36224Y491552D03*
X43824D03*
X36282Y499319D03*
X43882D03*
X722268Y35902D03*
X721192Y528243D03*
X729868Y35902D03*
X728792Y528243D03*
X1390595Y101089D03*
X1382995D03*
X1385800Y512000D03*
X1378200D03*
X1464300Y598500D03*
X1456700D03*
G54D171*
X1284290Y227739D03*
G54D51*
X-1950Y457450D03*
X-6550Y493850D03*
X85467Y302966D03*
X76500Y347900D03*
X84164Y380790D03*
X305817Y112075D03*
X313267Y115125D03*
X721921Y258921D03*
X718246Y258806D03*
X831125Y119452D03*
X829466Y109026D03*
X841741Y173258D03*
X942425Y128074D03*
X955425Y112075D03*
X962875Y115125D03*
G54D180*
X1371874Y494665D03*
X1588510Y130663D03*
X1587477Y144569D03*
X1593420Y131800D03*
X1592816Y140550D03*
X1593401Y145489D03*
X1634358Y180527D03*
X1868541Y138200D03*
G54D117*
X665396Y12500D03*
Y14469D03*
Y16437D03*
Y18406D03*
Y20374D03*
X676700D03*
Y18406D03*
Y16437D03*
Y14469D03*
Y12500D03*
X665795Y576493D03*
Y578462D03*
Y580430D03*
Y582399D03*
Y584367D03*
X677099D03*
Y582399D03*
Y580430D03*
Y578462D03*
Y576493D03*
X1782548Y89000D03*
Y90968D03*
Y92937D03*
X1793852Y90968D03*
Y89000D03*
Y87031D03*
Y92937D03*
X1782548Y85063D03*
X1793852D03*
X1782548Y87031D03*
X1812848Y155563D03*
X1824152D03*
X1812848Y159500D03*
Y161468D03*
Y163437D03*
X1824152Y161468D03*
Y159500D03*
Y157531D03*
Y163437D03*
X1812848Y157531D03*
G54D15*
X-16362Y462160D03*
Y478340D03*
X-11242Y462160D03*
X-13802D03*
X-8682D03*
X-11242Y478340D03*
X-13802D03*
X-8682D03*
X1700080Y68600D03*
X1697520D03*
X1694960D03*
X1692400D03*
X1689840D03*
X1687280D03*
X1684720D03*
X1682160D03*
Y46400D03*
X1684720D03*
X1687280D03*
X1689840D03*
X1692400D03*
X1694960D03*
X1697520D03*
X1700080D03*
X1652160Y437500D03*
Y421320D03*
X1657280Y437500D03*
Y421320D03*
X1654720Y437500D03*
Y421320D03*
X1659840D03*
Y437500D03*
G54D60*
X94683Y-5822D03*
Y31978D03*
Y69778D03*
Y532955D03*
Y570755D03*
Y608555D03*
X637793Y-5822D03*
Y31978D03*
Y69778D03*
Y532955D03*
Y570755D03*
Y608555D03*
X744293Y-5822D03*
Y31978D03*
Y69778D03*
Y570755D03*
Y532955D03*
Y608555D03*
X1287403Y-5822D03*
Y31978D03*
Y69778D03*
Y570755D03*
Y532955D03*
Y608555D03*
G54D135*
X1241963Y132677D03*
X1233463Y128927D03*
Y136427D03*
X1574447Y291724D03*
X1565947Y287974D03*
Y295474D03*
X1650250Y217650D03*
Y225150D03*
X1658750Y221400D03*
G54D252*
X1660158Y534035D03*
X1788110D03*
G54D24*
X21464Y-11490D03*
X2661Y485075D03*
X-4896Y485081D03*
X1347816Y43361D03*
G54D162*
X1261381Y427008D03*
X1253042Y422650D03*
G54D261*
X1733096Y588640D03*
X1727190D03*
X1895673Y155900D03*
X1893705D03*
X1891736D03*
X1897642D03*
X1921264D03*
X1905516D03*
X1911421D03*
X1913390D03*
X1917327D03*
X1915358D03*
X1919295D03*
X1899610D03*
X1903547D03*
X1909453D03*
X1901579D03*
X1907484D03*
G54D207*
X1475098Y397067D03*
X1476732Y387224D03*
Y399035D03*
X1480000Y387224D03*
Y395098D03*
Y399035D03*
X1481634Y385256D03*
Y389193D03*
Y393130D03*
Y401004D03*
X1481437Y376988D03*
X1481634Y381319D03*
X1484622Y375979D03*
X1483071Y378957D03*
X1475098Y385256D03*
X1480000Y383287D03*
X1478366Y381319D03*
Y385256D03*
X1476732Y383287D03*
X1481634Y397067D03*
X1478366D03*
X1480000Y379350D03*
X1475098Y393130D03*
X1478366Y389193D03*
X1476732Y395098D03*
X1480000Y391161D03*
X1478366Y393130D03*
X1475098Y389193D03*
X1476732Y391161D03*
X1475098Y401004D03*
X1480000Y402972D03*
X1478366Y401004D03*
X1476732Y402972D03*
X1475098Y404941D03*
Y420689D03*
Y428563D03*
Y432500D03*
Y440374D03*
X1476732Y410846D03*
Y414783D03*
Y450217D03*
X1478366Y404941D03*
Y420689D03*
Y428563D03*
Y432500D03*
Y440374D03*
X1480000Y410846D03*
Y414783D03*
Y450217D03*
X1481634Y404941D03*
Y408878D03*
Y412815D03*
Y416752D03*
Y420689D03*
Y424626D03*
Y428563D03*
Y432500D03*
Y436437D03*
Y440374D03*
Y444311D03*
Y448248D03*
Y452185D03*
Y456122D03*
Y460059D03*
Y463996D03*
X1475098D03*
X1478366D03*
X1476732Y462028D03*
X1480000D03*
X1475098Y460059D03*
X1478366D03*
X1476732Y458091D03*
X1480000D03*
X1475098Y456122D03*
X1478366D03*
X1476732Y454154D03*
X1480000D03*
X1475098Y452185D03*
X1478366D03*
X1475098Y448248D03*
X1476732Y446280D03*
X1475098Y444311D03*
X1476732Y442343D03*
X1478366Y448248D03*
X1480000Y446280D03*
X1478366Y444311D03*
X1480000Y442343D03*
Y430531D03*
X1476732D03*
X1475098Y412815D03*
X1478366D03*
X1476732Y422657D03*
Y426594D03*
X1478366Y416752D03*
X1475098Y408878D03*
X1480000Y406909D03*
Y422657D03*
Y426594D03*
X1475098Y416752D03*
X1478366Y408878D03*
X1476732Y406909D03*
X1480000Y438406D03*
X1476732D03*
X1480000Y418720D03*
X1476732D03*
X1480000Y434469D03*
X1476732D03*
X1478366Y424626D03*
X1475098D03*
X1478366Y436437D03*
X1475098D03*
X1478366Y483681D03*
X1481634Y471870D03*
Y483681D03*
Y467933D03*
Y475807D03*
Y479744D03*
X1476732Y469902D03*
X1480000D03*
X1475098Y467933D03*
X1478366D03*
X1476732Y465965D03*
X1480000D03*
X1476732Y481713D03*
X1480000D03*
X1475098Y479744D03*
X1478366D03*
X1476732Y477776D03*
X1480000D03*
X1475098Y475807D03*
X1478366D03*
X1476732Y473839D03*
X1480000D03*
X1475098Y471870D03*
X1478366D03*
X1484622Y489021D03*
X1481634Y487618D03*
X1480000Y485650D03*
X1579902Y393130D03*
X1571732Y379350D03*
X1570378Y375979D03*
X1579902Y397067D03*
Y389193D03*
X1573366Y377382D03*
X1579902Y385256D03*
Y401004D03*
Y412815D03*
Y456122D03*
Y460059D03*
Y408878D03*
Y404941D03*
Y448248D03*
Y452185D03*
Y444311D03*
Y440374D03*
Y416752D03*
Y432500D03*
Y428563D03*
Y436437D03*
Y424626D03*
Y420689D03*
Y463996D03*
X1571732Y485650D03*
X1570378Y489021D03*
X1573366Y487618D03*
X1579902Y467933D03*
Y479744D03*
Y471870D03*
Y475807D03*
G54D126*
X714761Y210752D03*
X1019589Y104065D03*
G54D243*
X1599194Y429620D03*
G54D33*
X30857Y37344D03*
X31182Y68711D03*
X20757Y544000D03*
Y580000D03*
X144881Y224533D03*
Y256533D03*
Y288533D03*
Y320533D03*
Y352533D03*
Y384533D03*
X687243Y214000D03*
X794489Y224533D03*
Y256533D03*
Y320533D03*
Y288533D03*
Y352533D03*
X794439Y384533D03*
X1352332Y-6824D03*
X1352643Y25200D03*
X1354950Y384068D03*
X1356643Y572056D03*
Y603256D03*
G54D306*
X1901804Y557807D03*
Y576807D03*
X1919504Y557807D03*
Y576807D03*
X1901804Y594001D03*
Y613001D03*
X1919504Y594001D03*
Y613001D03*
G54D108*
X651950Y261750D03*
G54D61*
X49150Y6112D03*
Y4537D03*
Y2962D03*
Y1387D03*
Y-188D03*
Y-1762D03*
Y-3337D03*
Y-4912D03*
Y-6487D03*
Y-8062D03*
G54D271*
X1846100Y92325D03*
Y90750D03*
Y89175D03*
G54D52*
X28870Y503685D03*
X1377504Y62065D03*
X1776900Y86600D03*
G54D25*
X21522Y11815D03*
X737700Y295500D03*
G54D172*
X1285536Y330531D03*
G54D43*
X14812Y74840D03*
X14487Y43473D03*
X4387Y550129D03*
Y586129D03*
X128511Y262662D03*
Y230662D03*
Y294662D03*
Y326662D03*
Y358662D03*
Y390662D03*
X703613Y207871D03*
X778119Y230662D03*
Y262662D03*
Y326662D03*
Y294662D03*
Y358662D03*
X778069Y390662D03*
X1368702Y-12953D03*
X1369013Y19071D03*
X1371320Y377939D03*
X1373013Y565927D03*
Y597127D03*
G54D136*
X1279928Y207308D03*
X1288111Y199713D03*
G54D145*
X1253964Y297498D03*
X1237316Y312648D03*
G54D118*
X710650Y59390D03*
Y57421D03*
Y55453D03*
Y53484D03*
Y51516D03*
Y49547D03*
Y47579D03*
Y45610D03*
Y43642D03*
Y61358D03*
Y545640D03*
Y543671D03*
Y541703D03*
Y539734D03*
Y537766D03*
Y535797D03*
Y533829D03*
Y531860D03*
Y529892D03*
Y547608D03*
X1370850Y119340D03*
Y117371D03*
Y115403D03*
Y113434D03*
Y111466D03*
Y109497D03*
Y107529D03*
Y105560D03*
Y103592D03*
Y121308D03*
X1365650Y526003D03*
Y524034D03*
Y522066D03*
Y520097D03*
Y518129D03*
Y516160D03*
Y514192D03*
Y529940D03*
Y527971D03*
Y531908D03*
G54D154*
X1247619Y353586D03*
G54D226*
X1560365Y243947D03*
X1585165D03*
G54D190*
X1430570Y457961D03*
G54D253*
X1734413Y186937D03*
X1731264Y204236D03*
Y186937D03*
X1728114Y204236D03*
Y186937D03*
X1724965Y204236D03*
X1772209D03*
Y186937D03*
X1769059Y204236D03*
Y186937D03*
X1765909Y204236D03*
X1724965Y186937D03*
X1765909D03*
X1762760Y204236D03*
Y186937D03*
X1759610Y204236D03*
Y186937D03*
X1756461Y204236D03*
Y186937D03*
X1753311Y204236D03*
Y186937D03*
X1750161Y204236D03*
X1721815D03*
X1750161Y186937D03*
X1747012Y204236D03*
Y186937D03*
X1743862Y204236D03*
Y186937D03*
X1740713Y204236D03*
Y186937D03*
X1737563Y204236D03*
Y186937D03*
X1734413Y204236D03*
X1721815Y186937D03*
X1759646Y226756D03*
X1756496D03*
X1753347D03*
X1750197D03*
X1747047D03*
X1772244Y244105D03*
X1769095D03*
X1765945D03*
X1762795D03*
X1759646D03*
X1756496D03*
X1743898Y226756D03*
X1753347Y244105D03*
X1750197D03*
X1747047D03*
X1743898D03*
X1740748D03*
X1737599D03*
X1734449D03*
X1740748Y226756D03*
X1737599D03*
X1772244D03*
X1769095D03*
X1765945D03*
X1762795D03*
X1734449D03*
X1835201Y204236D03*
Y186937D03*
X1832051Y204236D03*
Y186937D03*
X1828902Y204236D03*
Y186937D03*
X1825752Y204236D03*
Y186937D03*
X1822602Y204236D03*
Y186937D03*
X1819453Y204236D03*
Y186937D03*
X1816303Y204236D03*
Y186937D03*
X1813154Y204236D03*
Y186937D03*
X1810004Y204236D03*
Y186937D03*
X1806854Y204236D03*
Y186937D03*
X1803705Y204236D03*
Y186937D03*
X1800555Y204236D03*
Y186937D03*
X1797406Y204236D03*
Y186937D03*
X1794256Y204236D03*
Y186937D03*
X1791106Y204236D03*
Y186937D03*
X1787957Y204236D03*
Y186937D03*
X1784807Y204236D03*
Y186937D03*
X1781658Y204236D03*
Y186937D03*
X1778508Y204236D03*
Y186937D03*
X1775358Y204236D03*
Y186937D03*
X1832087Y244105D03*
X1828937D03*
X1825788D03*
X1822638D03*
X1819488D03*
X1816339D03*
X1813189D03*
X1810040D03*
X1806890D03*
X1803740D03*
X1800591D03*
X1797441D03*
X1794292D03*
X1791142D03*
X1787992D03*
X1784843D03*
X1781693D03*
X1778543D03*
X1775394D03*
X1832087Y226756D03*
X1828937D03*
X1825788D03*
X1822638D03*
X1819488D03*
X1816339D03*
X1813189D03*
X1810040D03*
X1806890D03*
X1803740D03*
X1800591D03*
X1797441D03*
X1794292D03*
X1791142D03*
X1787992D03*
X1784843D03*
X1781693D03*
X1778543D03*
X1775394D03*
X1844650Y204236D03*
Y186937D03*
X1841500Y204236D03*
Y186937D03*
X1838350Y204236D03*
Y186937D03*
G54D208*
X1482673Y374030D03*
Y490970D03*
X1572327Y374030D03*
Y490970D03*
G54D244*
X1647186Y474076D03*
Y527817D03*
G54D280*
X1869250Y112630D03*
Y124450D03*
Y130360D03*
Y114600D03*
Y116570D03*
Y128390D03*
Y126420D03*
Y120510D03*
Y118540D03*
Y122480D03*
G54D307*
X1970787Y139055D03*
Y196535D03*
G54D217*
X1473888Y615130D03*
X1475660D03*
X1477431D03*
X1479203D03*
X1480975D03*
X1482746D03*
X1484518D03*
X1486290D03*
X1488061D03*
X1489833D03*
X1509426Y616398D03*
X1511198D03*
X1512969D03*
X1514741D03*
X1516513D03*
X1518284D03*
X1520056D03*
X1521828D03*
X1523599D03*
X1525371D03*
G54D70*
X104000Y243000D03*
Y254000D03*
X128450Y118700D03*
Y129700D03*
X727500Y93000D03*
Y104000D03*
X758603Y506177D03*
Y495177D03*
X1512959Y277400D03*
Y266400D03*
X1889400Y77300D03*
Y88300D03*
G54D34*
X20515Y31338D03*
X20840Y62705D03*
X10415Y537994D03*
Y573994D03*
X134539Y218527D03*
Y250527D03*
Y282527D03*
Y314527D03*
Y346527D03*
Y378527D03*
X697585Y220006D03*
X784147Y218527D03*
Y250527D03*
Y314527D03*
Y282527D03*
Y346527D03*
X784097Y378527D03*
X1362674Y-818D03*
X1362985Y31206D03*
X1365292Y390074D03*
X1366985Y578062D03*
Y609262D03*
G54D16*
X-17200Y516800D03*
Y513300D03*
X-16500Y493000D03*
Y489500D03*
X34719Y16717D03*
Y13217D03*
X43819Y13901D03*
Y17401D03*
X46845Y17442D03*
Y13942D03*
X-1347Y23809D03*
Y27309D03*
X40796Y17406D03*
Y13906D03*
X37739Y16712D03*
Y13212D03*
X34597Y24567D03*
Y28067D03*
X28871Y-20458D03*
Y-16958D03*
X-1080Y60600D03*
Y57100D03*
X34500Y51000D03*
Y54500D03*
X4522Y57858D03*
Y54358D03*
X8000Y275500D03*
Y272000D03*
X11000Y275500D03*
Y272000D03*
X41000Y271450D03*
Y267950D03*
X37000Y271450D03*
Y267950D03*
X8000Y299000D03*
Y295500D03*
X5000Y299000D03*
Y295500D03*
X-1278Y464071D03*
Y460571D03*
X-5590Y521840D03*
Y518340D03*
X-2390D03*
Y521840D03*
X-13500Y493000D03*
Y489500D03*
X-8990Y523040D03*
Y519540D03*
X-12690Y519590D03*
Y523090D03*
X23800Y516500D03*
Y513000D03*
X27300Y516500D03*
Y513000D03*
X16990Y525130D03*
Y521630D03*
X25388Y504477D03*
Y507977D03*
X20490Y525130D03*
Y521630D03*
X710Y521890D03*
Y518390D03*
X-9900Y489500D03*
Y493000D03*
X52906Y13926D03*
Y17426D03*
X55942Y17445D03*
Y13945D03*
X49880Y17415D03*
Y13915D03*
X106000Y11328D03*
Y14828D03*
X56540Y-20308D03*
Y-16808D03*
X53340Y-20296D03*
Y-16796D03*
X105898Y49250D03*
Y52750D03*
X108077Y86864D03*
Y90364D03*
X104289Y128454D03*
Y124954D03*
X103250Y265180D03*
Y261680D03*
X87500Y275500D03*
Y279000D03*
X80500Y275500D03*
Y279000D03*
X84000Y275500D03*
Y279000D03*
X77000Y275500D03*
Y279000D03*
X73500Y275500D03*
Y279000D03*
X86078Y266950D03*
Y270450D03*
X103500Y322500D03*
Y319000D03*
X100000Y322500D03*
Y319000D03*
X75600Y328600D03*
Y332100D03*
X57000Y341500D03*
X60000D03*
X66000D03*
X72000Y341800D03*
X69000D03*
X63000Y341500D03*
X92370Y327770D03*
Y331270D03*
X89220Y331230D03*
Y327730D03*
X91710Y339200D03*
X87500Y318500D03*
Y322000D03*
X91500Y317800D03*
Y321300D03*
X70800Y317050D03*
Y313550D03*
X55500Y316250D03*
Y312750D03*
X56000Y307500D03*
Y304000D03*
X66500Y313250D03*
Y316750D03*
X61000Y313250D03*
Y316750D03*
X80500Y322020D03*
Y318520D03*
X78000Y341050D03*
X75000Y341500D03*
X50900Y295300D03*
Y298800D03*
X56000Y300000D03*
Y296500D03*
X84000Y318520D03*
Y322020D03*
X74500Y317000D03*
Y313500D03*
X96000Y287700D03*
Y291200D03*
X94630Y363220D03*
Y359720D03*
X57000Y345000D03*
X60000D03*
X66000D03*
X72000Y345300D03*
X69000D03*
X63000Y345000D03*
X91710Y342700D03*
X94519Y349333D03*
Y345833D03*
X94630Y356850D03*
Y353350D03*
X94710Y370914D03*
Y367414D03*
X78000Y344550D03*
X75000Y345000D03*
X88300Y383110D03*
Y386610D03*
X93296Y387604D03*
Y384104D03*
X72000Y391500D03*
Y395000D03*
X52500Y398000D03*
Y401500D03*
X56000Y398000D03*
Y401500D03*
X59500Y398000D03*
Y401500D03*
X49000Y398100D03*
Y401600D03*
X95396Y373774D03*
Y377274D03*
X57500Y385500D03*
Y382000D03*
X77300Y386614D03*
Y383114D03*
X80800Y386614D03*
Y383114D03*
X54000Y385500D03*
Y382000D03*
X91996Y377274D03*
Y373774D03*
X70525Y465138D03*
Y468638D03*
X109500Y11328D03*
Y14828D03*
X116500D03*
Y11328D03*
X113000D03*
Y14828D03*
X109392Y49250D03*
Y52750D03*
X112500Y49150D03*
Y52650D03*
X116000D03*
Y49150D03*
X117354Y90529D03*
Y87029D03*
X114284D03*
Y90529D03*
X111189Y86821D03*
Y90321D03*
X153200Y195600D03*
Y199100D03*
X117475Y168300D03*
Y164800D03*
X119400Y271600D03*
Y275100D03*
X118164Y304915D03*
Y308415D03*
X117976Y368958D03*
Y372458D03*
X156392Y407500D03*
Y404000D03*
X442700Y271500D03*
Y275000D03*
X428000Y271500D03*
Y275000D03*
X436000Y271500D03*
Y275000D03*
X432000Y271500D03*
Y275000D03*
X439500Y271500D03*
Y275000D03*
X436100Y326800D03*
Y330300D03*
X433100Y326800D03*
Y330300D03*
X439100Y326800D03*
Y330300D03*
X442100Y326800D03*
Y330300D03*
X658700Y29100D03*
Y25600D03*
X611000Y116700D03*
Y120200D03*
Y113700D03*
Y110200D03*
X639320Y274550D03*
Y271050D03*
X636708Y277735D03*
X641228Y247796D03*
Y251296D03*
X646000Y259100D03*
Y255600D03*
X655000Y278100D03*
X658500D03*
X651500D03*
X649500Y255600D03*
Y259100D03*
X636400Y259000D03*
Y255500D03*
X636708Y281235D03*
X649000Y342000D03*
X654000D03*
X659000D03*
X655500Y293500D03*
Y290000D03*
X655000Y281600D03*
X658638Y291123D03*
Y287623D03*
X658500Y281600D03*
X661730Y290008D03*
Y293508D03*
X651000Y291000D03*
Y294500D03*
X651500Y281600D03*
X647500Y291000D03*
Y294500D03*
X649000Y345500D03*
X654000D03*
X659000D03*
X640500Y406500D03*
Y410000D03*
X637000Y406500D03*
Y410000D03*
X710150Y-5950D03*
Y-9450D03*
X712000Y29000D03*
Y32500D03*
X712500Y17500D03*
Y21000D03*
X708900D03*
Y17500D03*
X708500Y32500D03*
Y29000D03*
X672900Y30600D03*
X686000Y30750D03*
X689500D03*
X686700Y27950D03*
Y24450D03*
X700500Y29000D03*
Y32500D03*
X664300Y28050D03*
Y31550D03*
X713937Y-9548D03*
Y-6048D03*
X722000Y20250D03*
Y16750D03*
X715937Y20952D03*
Y17452D03*
X704500Y28700D03*
Y32200D03*
X667800Y31550D03*
Y28050D03*
X682500Y30750D03*
X672900Y34100D03*
X686000Y34250D03*
X689500D03*
X716500Y53250D03*
Y49750D03*
X682500Y34250D03*
X723500Y247500D03*
Y244000D03*
X718000Y224600D03*
Y221100D03*
X720500Y247500D03*
Y244000D03*
X723500Y252500D03*
Y256000D03*
X714000D03*
Y252500D03*
X711000Y256000D03*
Y252500D03*
X717000D03*
Y256000D03*
X720500D03*
Y252500D03*
X707500Y256000D03*
Y252500D03*
X676000Y278100D03*
X672500D03*
X673500Y295000D03*
Y291500D03*
X692470Y293640D03*
Y290140D03*
X684000Y342000D03*
X674000D03*
X701000Y335500D03*
Y332000D03*
X705000Y335500D03*
Y332000D03*
X679000Y342000D03*
X669000D03*
X717900Y309200D03*
Y312700D03*
X701000Y303500D03*
Y307000D03*
Y322500D03*
Y319000D03*
X664000Y342000D03*
X725400Y300450D03*
Y296950D03*
X676000Y281600D03*
X672500D03*
X684000Y345500D03*
X674000D03*
X679400Y371200D03*
Y367700D03*
X689900Y371200D03*
Y367700D03*
X679000Y345500D03*
X669000D03*
X664000D03*
X693200Y416775D03*
Y420275D03*
X696400Y416775D03*
Y420275D03*
X683400Y414700D03*
Y411200D03*
X712100Y515250D03*
Y518750D03*
X708500D03*
Y515250D03*
X700500D03*
Y518750D03*
X669400Y515700D03*
Y519200D03*
X686000Y514250D03*
Y517750D03*
X689500Y520750D03*
Y517250D03*
X683550Y511200D03*
Y507700D03*
X672400Y519250D03*
Y515750D03*
X704500Y515250D03*
Y518750D03*
X675500Y519250D03*
Y515750D03*
X679000Y514250D03*
Y517750D03*
X682500Y514250D03*
Y517750D03*
X716400Y538800D03*
Y535300D03*
X714600Y574500D03*
Y578000D03*
X711000Y574500D03*
Y578000D03*
X759000Y11250D03*
Y14750D03*
X766000D03*
Y11250D03*
X762500D03*
Y14750D03*
X726500Y20250D03*
Y16750D03*
X755500Y11250D03*
Y14750D03*
X759000Y49250D03*
Y52750D03*
X766000D03*
Y49250D03*
X762500D03*
Y52750D03*
X759000Y88611D03*
Y92111D03*
X762500Y88611D03*
Y92111D03*
X766000D03*
Y88611D03*
X755500Y49250D03*
Y52750D03*
Y88611D03*
Y92111D03*
X762300Y213100D03*
Y216600D03*
X766947Y207070D03*
Y210570D03*
X728291Y247500D03*
Y244000D03*
X761600Y245520D03*
Y249020D03*
X726500Y252500D03*
Y256000D03*
X740697Y260490D03*
Y256990D03*
X761850Y275560D03*
Y279060D03*
X742400Y277850D03*
X748700Y276350D03*
Y272850D03*
X747886Y263659D03*
Y260159D03*
X742128Y270902D03*
Y267402D03*
X765134Y271186D03*
Y274686D03*
X764341Y239542D03*
Y243042D03*
X746870Y286050D03*
Y289550D03*
X742400Y281350D03*
X734200Y297650D03*
Y301150D03*
X728900Y300450D03*
Y296950D03*
X743070Y289500D03*
Y286000D03*
X765582Y303588D03*
Y307088D03*
X768367Y337062D03*
Y340562D03*
X762350Y343730D03*
Y347230D03*
X768059Y369287D03*
Y372787D03*
X730100Y573950D03*
Y577450D03*
X726500Y574000D03*
Y577500D03*
X730100Y600500D03*
Y604000D03*
X726800D03*
Y600500D03*
X804200Y195600D03*
Y199100D03*
X809000Y407500D03*
Y404000D03*
X1080500Y272000D03*
Y275500D03*
X1088000Y272000D03*
Y275500D03*
X1077000Y272000D03*
Y275500D03*
X1091500Y272000D03*
Y275500D03*
X1094764Y271972D03*
Y275472D03*
X1084500Y272000D03*
Y275500D03*
X1084580Y326760D03*
Y330260D03*
X1087680Y326760D03*
Y330260D03*
X1095000Y326600D03*
Y330100D03*
X1091180Y326660D03*
Y330160D03*
X1076270Y335780D03*
Y332280D03*
X1255400Y116917D03*
Y120417D03*
Y113917D03*
Y110417D03*
X1228906Y140251D03*
Y136751D03*
X1225775Y140219D03*
Y136719D03*
X1279550Y111670D03*
Y115170D03*
Y119170D03*
Y122670D03*
X1276704Y507538D03*
Y504038D03*
X1275540Y513490D03*
Y516990D03*
X1273687Y507491D03*
Y503991D03*
X1268805Y508940D03*
Y505440D03*
X1272060Y513590D03*
Y517090D03*
X1339500Y90000D03*
Y93500D03*
X1322000Y88000D03*
Y91500D03*
X1326600Y80900D03*
Y77400D03*
X1325500Y91500D03*
Y88000D03*
X1341600Y501750D03*
Y505250D03*
X1323900Y504750D03*
Y508250D03*
X1326900D03*
Y504750D03*
X1338300Y501750D03*
Y505250D03*
X1335100Y501700D03*
Y505200D03*
X1330000Y508250D03*
Y504750D03*
X1387497Y-3011D03*
Y489D03*
X1384371Y-3020D03*
Y480D03*
X1378170Y8888D03*
Y12388D03*
X1379556Y19907D03*
Y16407D03*
X1384200Y31700D03*
X1371591Y88967D03*
Y92467D03*
X1368591Y92450D03*
Y88950D03*
X1360700D03*
Y92450D03*
X1350500Y92640D03*
Y89140D03*
X1351500Y77000D03*
Y80500D03*
X1347500D03*
Y77000D03*
X1356010Y45574D03*
Y42074D03*
X1343500Y90000D03*
Y93500D03*
X1347000Y90000D03*
Y93500D03*
X1374500Y73500D03*
Y70000D03*
X1378000Y73500D03*
Y70000D03*
X1370100Y79500D03*
Y76000D03*
X1364700Y88950D03*
Y92450D03*
X1366100Y79500D03*
Y76000D03*
X1344000Y80500D03*
Y77000D03*
X1374177Y61982D03*
Y65482D03*
X1384200Y35200D03*
X1376550Y113600D03*
Y110100D03*
X1344900Y505250D03*
Y501750D03*
X1396871Y505800D03*
Y509300D03*
X1392953Y509379D03*
Y505879D03*
X1371500Y526000D03*
X1401960Y524955D03*
X1391291Y531936D03*
Y528436D03*
X1400222Y554185D03*
Y550685D03*
X1352000Y560600D03*
Y564100D03*
X1371500Y529500D03*
X1401960Y528455D03*
X1398620Y530921D03*
Y534421D03*
X1398226Y543462D03*
Y539962D03*
X1395120Y530921D03*
Y534421D03*
X1385800Y612500D03*
Y609000D03*
X1352332Y620000D03*
Y616500D03*
X1383879Y619250D03*
Y615750D03*
X1420337Y42977D03*
Y39477D03*
X1416837Y42977D03*
Y39477D03*
X1458136D03*
Y42977D03*
X1454636Y39477D03*
Y42977D03*
X1464086Y39477D03*
Y42977D03*
X1438936Y39477D03*
Y42977D03*
X1426286Y39477D03*
Y42977D03*
X1435436Y39477D03*
Y42977D03*
X1429786Y39477D03*
Y42977D03*
X1445186Y39477D03*
Y42977D03*
X1448686Y39477D03*
Y42977D03*
X1430117Y287489D03*
Y283989D03*
X1461700Y395500D03*
Y399000D03*
X1458450Y365450D03*
Y361950D03*
X1460500Y386000D03*
Y382500D03*
Y392500D03*
Y389000D03*
X1453000Y377750D03*
Y381250D03*
X1453900Y398100D03*
Y394600D03*
X1441800Y366400D03*
Y362900D03*
X1451560Y418179D03*
Y421679D03*
Y428279D03*
Y424779D03*
X1425560Y523955D03*
X1428800Y524000D03*
X1432200Y524050D03*
X1422000Y524000D03*
X1405460Y524955D03*
X1455000Y540750D03*
Y537250D03*
X1458000Y540750D03*
Y537250D03*
X1425560Y527455D03*
X1428800Y527500D03*
X1432200Y527550D03*
X1448900Y540600D03*
Y537100D03*
X1452000D03*
Y540600D03*
X1439200Y534600D03*
Y531100D03*
X1436160Y554655D03*
Y558155D03*
X1422000Y527500D03*
X1432560Y558155D03*
Y554655D03*
X1405460Y528455D03*
X1527600Y-2500D03*
Y1000D03*
X1516900Y-2500D03*
Y1000D03*
X1520100Y-2500D03*
Y1000D03*
X1513700Y-2500D03*
Y1000D03*
X1486486Y39477D03*
Y42977D03*
X1491836Y39577D03*
Y43077D03*
X1495336Y39577D03*
Y43077D03*
X1477036Y39477D03*
Y42977D03*
X1473536Y39477D03*
Y42977D03*
X1467586Y39477D03*
Y42977D03*
X1482986Y39477D03*
Y42977D03*
X1498985Y143065D03*
Y146565D03*
X1493750Y140400D03*
Y143900D03*
X1519200Y206700D03*
Y203200D03*
X1518000Y218250D03*
X1511000D03*
X1518000Y221750D03*
X1511000D03*
X1504453Y302789D03*
Y299289D03*
X1507476Y302789D03*
Y299289D03*
X1510476Y302816D03*
Y299316D03*
X1513476D03*
Y302816D03*
X1516910Y323940D03*
Y327440D03*
X1523000Y347250D03*
Y343750D03*
X1526000D03*
Y347250D03*
X1517000D03*
Y343750D03*
X1520000Y347250D03*
Y343750D03*
X1487000Y347250D03*
Y343750D03*
X1496000D03*
Y347250D03*
X1499000Y343750D03*
Y347250D03*
X1493000Y343750D03*
Y347250D03*
X1490000D03*
Y343750D03*
X1483000Y347250D03*
Y343750D03*
X1472500D03*
Y347250D03*
X1477000Y343750D03*
Y347250D03*
X1480000Y343750D03*
Y347250D03*
X1508000D03*
Y343750D03*
X1514000Y347250D03*
Y343750D03*
X1511000Y347250D03*
Y343750D03*
X1505000Y347250D03*
Y343750D03*
X1502000D03*
Y347250D03*
X1472500Y354250D03*
Y350750D03*
X1494950Y353000D03*
Y356500D03*
X1516960Y352580D03*
Y356080D03*
X1502030Y585894D03*
Y582394D03*
X1466647Y580512D03*
Y577012D03*
X1502268Y604439D03*
Y607939D03*
X1466800Y615439D03*
Y611939D03*
X1466500Y604750D03*
Y608250D03*
X1494300Y618900D03*
Y622400D03*
X1502268Y615439D03*
Y611939D03*
X1498182Y603774D03*
Y607274D03*
X1494982Y603849D03*
Y607349D03*
X1554800Y-2600D03*
Y900D03*
X1564400Y-2600D03*
Y900D03*
X1558000Y-2600D03*
Y900D03*
X1561200Y-2600D03*
Y900D03*
X1540000Y-2500D03*
Y1000D03*
X1534000Y-2500D03*
Y1000D03*
X1543500Y-2500D03*
Y1000D03*
X1530800Y-2500D03*
Y1000D03*
X1548400Y-2600D03*
Y900D03*
X1551600Y-2600D03*
Y900D03*
X1586500Y87000D03*
Y90500D03*
X1585500Y94500D03*
X1589500Y90500D03*
Y87000D03*
X1582500Y94500D03*
X1579998Y39484D03*
Y42984D03*
X1576498Y39484D03*
Y42984D03*
X1585948Y39484D03*
Y42984D03*
X1589448Y39484D03*
Y42984D03*
X1557398Y39684D03*
Y43184D03*
X1548248Y39484D03*
Y42984D03*
X1560898Y39684D03*
Y43184D03*
X1567048Y39484D03*
Y42984D03*
X1570548Y39484D03*
Y42984D03*
X1551748Y39484D03*
Y42984D03*
X1584183Y112179D03*
Y115679D03*
X1580920Y115685D03*
Y112185D03*
X1587222Y115669D03*
Y112169D03*
X1585500Y98000D03*
X1582500D03*
X1576731Y128410D03*
Y131910D03*
X1579000Y185250D03*
Y188750D03*
Y182250D03*
Y178750D03*
X1553000Y162900D03*
Y159400D03*
X1579000Y196750D03*
Y193250D03*
X1541000Y279750D03*
X1548000D03*
X1534000D03*
X1537500D03*
X1540000Y250750D03*
Y254250D03*
X1537000D03*
Y250750D03*
X1550852Y246702D03*
Y243202D03*
X1533000Y257600D03*
Y261100D03*
X1533900Y250750D03*
Y254250D03*
X1543399Y251250D03*
Y254750D03*
X1544500Y279750D03*
X1554400Y258800D03*
Y262300D03*
Y258800D03*
Y255300D03*
X1577500Y334250D03*
Y330750D03*
Y327750D03*
Y324250D03*
X1540957Y337323D03*
Y340823D03*
X1547651Y336246D03*
Y339746D03*
X1560500Y338500D03*
Y335000D03*
X1553500Y338250D03*
Y334750D03*
X1556500Y338250D03*
Y334750D03*
X1543957Y337323D03*
Y340823D03*
X1541000Y283250D03*
X1548000D03*
X1567500Y309750D03*
Y306250D03*
X1534000Y283250D03*
X1537500D03*
X1535250Y317800D03*
Y314300D03*
X1577500Y296000D03*
Y299500D03*
X1544500Y283250D03*
X1545500Y343750D03*
Y347250D03*
X1556500Y343750D03*
Y347250D03*
X1553500Y343750D03*
Y347250D03*
X1560500Y343750D03*
Y347250D03*
X1550500D03*
Y343750D03*
X1529000Y347250D03*
Y343750D03*
X1535000Y347250D03*
Y343750D03*
X1542500D03*
Y347250D03*
X1538000D03*
Y343750D03*
X1532000D03*
Y347250D03*
X1574500Y587500D03*
X1571493D03*
X1562500Y583300D03*
Y586800D03*
X1568212Y587331D03*
X1577000Y610560D03*
Y607060D03*
X1573520Y607090D03*
Y610590D03*
X1577000Y613500D03*
Y617000D03*
X1574500Y591000D03*
X1571493D03*
X1539000Y591919D03*
Y595419D03*
X1573500Y617000D03*
Y613500D03*
X1568212Y590831D03*
X1542500Y591919D03*
Y595419D03*
X1530850Y603650D03*
Y607150D03*
X1649900Y81750D03*
Y85250D03*
X1643629Y83308D03*
Y86808D03*
X1614366Y87329D03*
Y90829D03*
X1636500Y87500D03*
Y91000D03*
X1628500Y90000D03*
Y86500D03*
X1625500Y86750D03*
Y90250D03*
X1598849Y90788D03*
Y87288D03*
X1602000Y87250D03*
Y90750D03*
X1643900Y70300D03*
Y73800D03*
X1650800Y70300D03*
Y73800D03*
X1647500Y70300D03*
Y73800D03*
X1595500Y87250D03*
Y90750D03*
X1592500Y90500D03*
Y87000D03*
X1621949Y83888D03*
Y87388D03*
X1618449Y83888D03*
Y87388D03*
X1605000Y76250D03*
Y79750D03*
X1617393Y41527D03*
Y45027D03*
X1613893Y41527D03*
Y45027D03*
X1595398Y39484D03*
Y42984D03*
X1598898Y39484D03*
Y42984D03*
X1604848Y39479D03*
Y42979D03*
X1608348Y39479D03*
Y42979D03*
X1647852Y189229D03*
Y192729D03*
X1650852D03*
Y189229D03*
X1630154Y214948D03*
Y211448D03*
X1606934Y191791D03*
Y188291D03*
X1603934Y192041D03*
Y188541D03*
X1612934Y191791D03*
Y188291D03*
X1609934Y191791D03*
Y188291D03*
X1639811Y191803D03*
Y188303D03*
X1596000Y187850D03*
Y184350D03*
X1599000Y187850D03*
Y184350D03*
X1618623Y191226D03*
Y187726D03*
X1621623Y191226D03*
Y187726D03*
X1624972Y192756D03*
Y189256D03*
X1636811Y191803D03*
Y188303D03*
X1645000Y217850D03*
X1630418Y192807D03*
Y189307D03*
X1633711Y192804D03*
Y189304D03*
X1645400Y228350D03*
Y224850D03*
X1599201Y249642D03*
Y253142D03*
X1605819Y259329D03*
Y262829D03*
X1591174Y227582D03*
Y231082D03*
X1645000Y221350D03*
X1591500Y329250D03*
Y325750D03*
X1648200Y336750D03*
Y340250D03*
X1645000Y336750D03*
Y340250D03*
X1645650Y345250D03*
Y348750D03*
X1648650D03*
Y345250D03*
X1624200Y403500D03*
X1622550Y358200D03*
Y354700D03*
X1616900Y403400D03*
X1620700D03*
X1616890Y399580D03*
Y396080D03*
X1633400Y372900D03*
Y369400D03*
X1594201Y384066D03*
Y387566D03*
X1594451Y398528D03*
Y395028D03*
X1620000Y349250D03*
Y345750D03*
X1649800Y452300D03*
Y448800D03*
X1627800Y464100D03*
X1643430Y434280D03*
Y437780D03*
X1624200Y407000D03*
X1606500Y405250D03*
Y408750D03*
X1609500D03*
Y405250D03*
X1616900Y406900D03*
X1620700D03*
X1643301Y418255D03*
Y414755D03*
X1622383Y492026D03*
Y495526D03*
X1627800Y467600D03*
X1631538Y530500D03*
Y534000D03*
X1628038Y530500D03*
Y534000D03*
X1621295Y533812D03*
Y530312D03*
X1624538Y534000D03*
Y530500D03*
X1656500Y86000D03*
Y89500D03*
X1653000Y81750D03*
Y85250D03*
X1708000Y59500D03*
Y56000D03*
X1711700Y62000D03*
Y58500D03*
X1705000Y56000D03*
Y59500D03*
X1663700Y87800D03*
Y84300D03*
X1711300Y65400D03*
Y68900D03*
X1667916Y58116D03*
Y54616D03*
X1704900Y69768D03*
Y66268D03*
X1654100Y70300D03*
Y73800D03*
X1705250Y48400D03*
Y44900D03*
X1700000Y102000D03*
Y105500D03*
X1696650Y102000D03*
Y105500D03*
X1706100Y128450D03*
Y124950D03*
X1676849Y189288D03*
Y192788D03*
X1679849Y189288D03*
Y192788D03*
X1667349Y189288D03*
Y192788D03*
X1659949Y189288D03*
Y192788D03*
X1664349Y189288D03*
Y192788D03*
X1703350Y174350D03*
Y177850D03*
X1710650Y166200D03*
Y169700D03*
X1683340Y177101D03*
Y180601D03*
X1653949Y189288D03*
Y192788D03*
X1656949Y189288D03*
Y192788D03*
X1662000Y328750D03*
Y332250D03*
X1656400Y336750D03*
Y340250D03*
X1657500Y462550D03*
X1661000D03*
X1656000Y451750D03*
Y448250D03*
X1659000Y451750D03*
Y448250D03*
X1657500Y466050D03*
X1661000D03*
X1693019Y514752D03*
Y518252D03*
X1690000Y518250D03*
Y514750D03*
X1702830Y512550D03*
Y509050D03*
X1718500Y79750D03*
Y83250D03*
X1722000Y73250D03*
Y76750D03*
X1714850Y74278D03*
Y77778D03*
X1729500Y54500D03*
Y51000D03*
X1726500Y54500D03*
Y51000D03*
X1723500D03*
Y54500D03*
X1762000Y76250D03*
Y79750D03*
X1714700Y58500D03*
Y62000D03*
X1718500Y72750D03*
Y76250D03*
X1758780Y92870D03*
X1755580D03*
X1765500Y76250D03*
Y79750D03*
X1773708Y109776D03*
Y113276D03*
X1758780Y96370D03*
X1755580D03*
X1714129Y173131D03*
Y169631D03*
X1724200Y510100D03*
Y506600D03*
X1715461Y587223D03*
Y590723D03*
X1833100Y4200D03*
Y7700D03*
X1829900Y80450D03*
Y83950D03*
X1824350Y88150D03*
Y91650D03*
X1833000Y83950D03*
Y80450D03*
X1824350Y94450D03*
X1793000Y149000D03*
Y152500D03*
X1819348Y145937D03*
Y149437D03*
X1815348D03*
Y145937D03*
X1802485Y136539D03*
Y140039D03*
X1804720Y106570D03*
Y103070D03*
X1808400Y117300D03*
Y120800D03*
X1811900Y117500D03*
Y121000D03*
X1787500Y152500D03*
Y149000D03*
X1780500Y109750D03*
Y113250D03*
X1822848Y145937D03*
Y149437D03*
X1811348Y145937D03*
Y149437D03*
X1824350Y97950D03*
X1777000Y109750D03*
Y113250D03*
X1786000Y158000D03*
Y161500D03*
X1836000Y158300D03*
Y161800D03*
X1834000Y532500D03*
Y529000D03*
X1782000Y588500D03*
Y585000D03*
X1780756Y576990D03*
Y573490D03*
X1835000Y586250D03*
Y582750D03*
Y575750D03*
Y579250D03*
X1787500Y595000D03*
Y591500D03*
X1884018Y45564D03*
Y49064D03*
X1880630Y45611D03*
Y49111D03*
X1886590Y69285D03*
Y72785D03*
X1890090Y69285D03*
Y72785D03*
X1883090Y69285D03*
Y72785D03*
X1842964Y104926D03*
Y101426D03*
X1859163Y141698D03*
Y145198D03*
X1866500Y144250D03*
Y140750D03*
X1875500Y147750D03*
Y144250D03*
X1878500Y147750D03*
Y144250D03*
X1881500Y147750D03*
Y144250D03*
X1870000D03*
Y140750D03*
X1839598Y101484D03*
Y104984D03*
X1897640Y140100D03*
Y136600D03*
X1862500Y153500D03*
Y150000D03*
X1856329Y107042D03*
Y103542D03*
X1881400Y189350D03*
Y192850D03*
X1897760Y202210D03*
Y198710D03*
X1881400Y181350D03*
Y177850D03*
X1842500Y169500D03*
Y166000D03*
X1875900Y158850D03*
Y162350D03*
Y168850D03*
Y165350D03*
X1840000Y526000D03*
Y522500D03*
X1839000Y513000D03*
Y509500D03*
X1838900Y502300D03*
Y498800D03*
X1881806Y588061D03*
X1840000Y532500D03*
Y529000D03*
X1862500Y574250D03*
Y577750D03*
Y586250D03*
Y582750D03*
X1868000Y584250D03*
Y580750D03*
X1862000Y566250D03*
Y569750D03*
X1871100Y586400D03*
X1873150Y561050D03*
Y557550D03*
X1876650Y561050D03*
Y557550D03*
X1881806Y591561D03*
X1871100Y589900D03*
X1922800Y90900D03*
Y87400D03*
X1925097Y115420D03*
Y111920D03*
X1916094Y103696D03*
Y107196D03*
X1931000Y150500D03*
Y147000D03*
X1916094Y110696D03*
Y107196D03*
X1912894Y107146D03*
Y110646D03*
Y107146D03*
Y103646D03*
X1921144Y115344D03*
Y118844D03*
Y115344D03*
Y111844D03*
X1921139Y105424D03*
Y108924D03*
X1900200Y130000D03*
Y133500D03*
Y123600D03*
Y127100D03*
X1928000Y195850D03*
Y199350D03*
X1922800Y196050D03*
Y199550D03*
X1919800Y196050D03*
Y199550D03*
X1937909Y183346D03*
Y186846D03*
X1941609D03*
Y183346D03*
X1914900Y201350D03*
Y197850D03*
X1911400Y201350D03*
Y197850D03*
X1918200Y548600D03*
Y545100D03*
G54D127*
X684400Y228100D03*
X1343072Y40715D03*
X1356960Y9620D03*
X1360800Y368200D03*
X1357200Y556000D03*
X1362482Y618600D03*
G54D163*
X1261528Y438443D03*
X1253007Y431370D03*
G54D262*
X1724041Y590805D03*
Y594742D03*
Y592773D03*
Y596711D03*
Y598679D03*
X1889300Y164242D03*
Y162273D03*
Y172116D03*
Y176053D03*
Y160305D03*
Y178021D03*
Y170147D03*
Y181958D03*
Y185895D03*
Y183927D03*
Y158336D03*
Y166210D03*
Y168179D03*
Y187864D03*
Y174084D03*
Y179990D03*
G54D235*
X1602717Y104467D03*
X1605867Y110766D03*
X1602717Y107617D03*
X1605867Y104467D03*
Y107617D03*
X1609016Y110766D03*
Y104467D03*
Y107617D03*
X1602717Y110766D03*
Y170609D03*
Y167459D03*
X1605867D03*
Y170609D03*
X1602717Y164310D03*
X1609016D03*
X1605867D03*
X1609016Y167459D03*
Y170609D03*
X1668859Y104467D03*
Y110766D03*
X1662560D03*
X1665709D03*
Y107617D03*
X1662560D03*
X1665709Y104467D03*
X1668859Y107617D03*
X1662560Y104467D03*
X1668859Y170609D03*
X1665709Y167459D03*
X1668859D03*
Y164310D03*
X1662560D03*
X1665709D03*
Y170609D03*
X1662560D03*
Y167459D03*
G54D181*
X1405750Y568569D03*
Y585891D03*
G54D109*
X652400Y266849D03*
X681500Y260248D03*
G54D53*
X28870Y507085D03*
X1377504Y65465D03*
X1776900Y90000D03*
G54D26*
X25122Y11815D03*
X741300Y295500D03*
G54D191*
X1421619Y461733D03*
X1412123Y465283D03*
G54D272*
X1838400Y92325D03*
Y89175D03*
Y90750D03*
G54D146*
X1254493Y290195D03*
G54D35*
X14487Y33945D03*
X14812Y65312D03*
X4387Y540601D03*
Y576601D03*
X128511Y221134D03*
Y253134D03*
Y285134D03*
Y317134D03*
Y349134D03*
Y381134D03*
X703613Y217399D03*
X778119Y221134D03*
Y253134D03*
Y317134D03*
Y285134D03*
Y349134D03*
X778069Y381134D03*
X1368702Y-3425D03*
X1369013Y28599D03*
X1371320Y387467D03*
X1373013Y575455D03*
Y606655D03*
G54D281*
X1880510Y133750D03*
X1886420D03*
X1884450D03*
X1882480D03*
X1876570D03*
X1874600D03*
X1872630D03*
X1878540D03*
X1890360D03*
X1888390D03*
G54D119*
X700484Y41350D03*
X702453D03*
X704421D03*
X706390D03*
X708358D03*
X690642D03*
X692610D03*
X694579D03*
X696547D03*
X698516D03*
X700484Y527600D03*
X702453D03*
X704421D03*
X706390D03*
X708358D03*
X690642D03*
X692610D03*
X694579D03*
X696547D03*
X698516D03*
X1360684Y101300D03*
X1362653D03*
X1364621D03*
X1366590D03*
X1368558D03*
X1350842D03*
X1352810D03*
X1354779D03*
X1356747D03*
X1358716D03*
X1355484Y511900D03*
X1357453D03*
X1359421D03*
X1361390D03*
X1363358D03*
X1345642D03*
X1347610D03*
X1349579D03*
X1351547D03*
X1353516D03*
G54D173*
X1282412Y386838D03*
X1291431Y382075D03*
X1284195Y379437D03*
X1288657Y392100D03*
G54D155*
X1254441Y355073D03*
X1265918Y348135D03*
X1246918Y362262D03*
G54D137*
X1245946Y265866D03*
G54D245*
X1634611Y506852D03*
Y510789D03*
Y514726D03*
Y518663D03*
Y479293D03*
Y483230D03*
Y487167D03*
Y491104D03*
Y495041D03*
Y498978D03*
Y502915D03*
Y522600D03*
X1656611Y510789D03*
Y514726D03*
Y518663D03*
Y479293D03*
Y483230D03*
Y487167D03*
Y522600D03*
Y491104D03*
Y495041D03*
Y498978D03*
Y502915D03*
Y506852D03*
G54D236*
X1623812Y235469D03*
G54D44*
X18228Y178386D03*
X-1969D03*
G54D218*
X1472332Y603850D03*
Y605622D03*
Y607393D03*
Y609165D03*
Y610937D03*
Y612708D03*
X1507870Y605118D03*
Y606890D03*
Y608661D03*
Y610433D03*
Y612205D03*
Y613976D03*
G54D71*
X105300Y272900D03*
X101550Y281400D03*
X97800Y272900D03*
X106200Y303900D03*
X98700D03*
X102450Y312400D03*
X1217275Y127924D03*
X1224775D03*
X1221025Y136424D03*
X1564831Y331926D03*
X1572331D03*
X1568581Y323426D03*
X1652485Y207858D03*
X1659985D03*
X1656235Y199358D03*
X1871150Y565850D03*
X1867400Y574350D03*
X1874900D03*
X1933500Y540000D03*
X1926000D03*
X1929750Y548500D03*
G54D227*
X1550750Y270437D03*
Y268469D03*
Y266500D03*
Y264531D03*
Y262563D03*
X1537250D03*
Y264531D03*
Y266500D03*
Y268469D03*
Y270437D03*
G54D308*
X1960433Y213997D03*
Y235451D03*
G54D17*
X-16000Y534300D03*
Y570300D03*
X21652Y8515D03*
X25152D03*
X25558Y-8431D03*
X22058D03*
X46550Y20464D03*
X31907Y-19337D03*
X35407D03*
X31899Y-14906D03*
X35399D03*
X31599Y17909D03*
X28099D03*
X9100Y22344D03*
X12600D03*
X20100D03*
X16600D03*
X28099Y14409D03*
X31599D03*
X45113Y-16137D03*
X20411Y50456D03*
X16911D03*
X-1000Y78900D03*
X2500D03*
X21347Y81785D03*
X17847D03*
X9823Y53541D03*
X13323D03*
X20425Y53711D03*
X16925D03*
X2200Y75650D03*
X-1300D03*
X2170Y51080D03*
X5670D03*
X4742Y270027D03*
X1242D03*
X9450Y451000D03*
X5950D03*
X33678Y426855D03*
X30178D03*
X30305Y436582D03*
X33805D03*
X28500Y500500D03*
X25000D03*
X-569Y488479D03*
X-4069D03*
X6353Y488492D03*
X2853D03*
X28500Y492500D03*
X25000D03*
X-13400Y499300D03*
X-9900D03*
X-13400Y502800D03*
X-9900D03*
X-10500Y506300D03*
X-14000D03*
X-10500Y512300D03*
X-14000D03*
X-10500Y509300D03*
X-14000D03*
X28500Y496500D03*
X25000D03*
X-1093Y467071D03*
X2407D03*
X-12500Y534300D03*
Y570300D03*
X10200Y528800D03*
X6700D03*
X0D03*
X3500D03*
X-7746Y587765D03*
X-11246D03*
X10780Y559064D03*
X7280D03*
X-4800Y564000D03*
X-8300D03*
X-1000D03*
X2500D03*
X10000D03*
X6500D03*
X30422Y562532D03*
X33922D03*
X24265Y529069D03*
X27765D03*
X-3800Y528800D03*
X-7300D03*
X-7483Y551374D03*
X-10983D03*
X-10842Y554878D03*
X-7342D03*
X8678Y593224D03*
X5178D03*
X-9785Y590965D03*
X-6285D03*
X53704Y8216D03*
X57204D03*
X50050Y20464D03*
X63712Y2888D03*
X60212D03*
X57204Y4716D03*
X53704D03*
X58389Y-13808D03*
X54889D03*
X58389Y-10601D03*
X54889D03*
X48613Y-16137D03*
X58200Y95000D03*
X54700D03*
X58200Y91500D03*
X54700D03*
X101000Y118000D03*
X104500D03*
Y121500D03*
X101000D03*
X52100Y148500D03*
X55600D03*
X58200Y105500D03*
X54700D03*
X58200Y112500D03*
X54700D03*
X58200Y116000D03*
X54700D03*
X58200Y140500D03*
X54700D03*
X58200Y133500D03*
X54700D03*
X58200Y137000D03*
X54700D03*
X58200Y144000D03*
X54700D03*
X58200Y126500D03*
X54700D03*
X58200Y123000D03*
X54700D03*
X58200Y130000D03*
X54700D03*
X58200Y119500D03*
X54700D03*
X58200Y109000D03*
X54700D03*
X58200Y102000D03*
X54700D03*
X58200Y98500D03*
X54700D03*
X72700Y171900D03*
X69200D03*
X48300Y157500D03*
X51800D03*
X91600Y162300D03*
X95100D03*
X63600Y163400D03*
X67100D03*
X56500Y200500D03*
X53000D03*
X56500Y204000D03*
X53000D03*
X94250Y267122D03*
X90750D03*
X94278Y270852D03*
X90778D03*
X93700Y262300D03*
X97200D03*
X62500Y275500D03*
X66000D03*
X59500D03*
X56000D03*
X93858Y240300D03*
X97358D03*
X106698Y219572D03*
X108462Y316200D03*
X98500Y298500D03*
X102000D03*
X55500Y334500D03*
X59000D03*
X91000Y297000D03*
X87500D03*
Y300500D03*
X91000D03*
X87500Y289000D03*
X91000D03*
Y285300D03*
X87500D03*
Y293500D03*
X91000D03*
X87500Y313500D03*
X91000D03*
X87500Y309500D03*
X91000D03*
Y306000D03*
X87500D03*
X73000Y324500D03*
X76500D03*
X55500Y323500D03*
X59000D03*
Y327000D03*
X55500D03*
X84650Y338700D03*
X81150D03*
X59000Y280500D03*
X62500D03*
X91000Y282200D03*
X87500D03*
X81700Y343900D03*
X85200D03*
X58000Y351500D03*
X54500D03*
Y348400D03*
X58000D03*
X68500Y388600D03*
X72000D03*
X61300Y392100D03*
X57800D03*
X54500Y354600D03*
X58000D03*
X85200Y347000D03*
X81700D03*
X68500Y385500D03*
X72000D03*
X61000Y385400D03*
X64500D03*
X59900Y388600D03*
X63400D03*
X74648Y461201D03*
X71148D03*
X78100Y465511D03*
X74600D03*
X123892Y13078D03*
X120392D03*
X123892Y50878D03*
X120392D03*
X123907Y87248D03*
X120407D03*
X159700Y199100D03*
X156200D03*
X159700Y195600D03*
X156200D03*
X123100Y209200D03*
X126600D03*
X120179Y210345D03*
X116679D03*
X134124Y209533D03*
X130624D03*
X150400Y208300D03*
X153900D03*
X110088Y252322D03*
X113588D03*
X110198Y219572D03*
X133924Y273300D03*
X130424D03*
X124124Y272533D03*
X127624D03*
X117000Y263500D03*
X113500D03*
X113100Y266763D03*
X116600D03*
X133788Y269786D03*
X130288D03*
X153200Y272900D03*
X156700D03*
X113100Y234713D03*
X116600D03*
X134324Y241333D03*
X130824D03*
X116900Y231450D03*
X113400D03*
X134378Y237702D03*
X130878D03*
X120177Y242977D03*
X116677D03*
X123624Y240533D03*
X127124D03*
X149710Y240512D03*
X153210D03*
X110817Y283595D03*
X114317D03*
X111962Y316200D03*
X113299Y295373D03*
X109799D03*
X111000Y301000D03*
X114500D03*
X134250Y302000D03*
X130750D03*
X134519Y337550D03*
X131019D03*
X121519Y336550D03*
X125019D03*
X134250Y334000D03*
X130750D03*
X113100Y330563D03*
X116600D03*
X123624Y304533D03*
X127124D03*
X134124Y305533D03*
X130624D03*
X117000Y327300D03*
X113500D03*
X150600Y306100D03*
X154100D03*
X116995Y338517D03*
X113495D03*
X149909Y337400D03*
X153409D03*
X109866Y348586D03*
X113366D03*
X113200Y402500D03*
X116700D03*
X110120Y378710D03*
X113620D03*
X114500Y360500D03*
X111000D03*
Y363700D03*
X114500D03*
X134250Y365900D03*
X130750D03*
X123871Y368603D03*
X127371D03*
X134369Y369241D03*
X130869D03*
X147710Y369400D03*
X151210D03*
X117020Y392130D03*
X113520D03*
X132111Y402698D03*
X128611D03*
X132131Y399498D03*
X128631D03*
X151343Y418959D03*
X154843D03*
X151314Y422658D03*
X154814D03*
X163375Y404446D03*
X159875D03*
X163375Y407446D03*
X159875D03*
X116600Y414700D03*
X113100D03*
X116600Y411700D03*
X113100D03*
X116700Y408600D03*
X113200D03*
X116700Y405500D03*
X113200D03*
X123792Y507300D03*
X120292D03*
X123492Y551400D03*
X119992D03*
X123692Y589200D03*
X120192D03*
X449100Y273300D03*
X445600D03*
X432000Y268000D03*
X428500D03*
X461500Y300500D03*
X458000D03*
X461400Y287500D03*
X457900D03*
X461400Y290500D03*
X457900D03*
X457248Y281341D03*
X460748D03*
X458000Y303500D03*
X461500D03*
Y297500D03*
X458000D03*
X461400Y284500D03*
X457900D03*
X461300Y293700D03*
X457800D03*
X595500Y102000D03*
X599000D03*
X655500Y25500D03*
X652000D03*
X660893Y35488D03*
X657393D03*
X607500Y120200D03*
X611000D03*
Y113700D03*
X607500D03*
X611000Y116700D03*
X607500D03*
Y110200D03*
X611000D03*
X661005Y134450D03*
X657505D03*
X661005Y137650D03*
X657505D03*
X640566Y278324D03*
X644066D03*
X649500Y275300D03*
X646000D03*
Y265000D03*
X649500D03*
Y272000D03*
X646000D03*
X650000Y268300D03*
X646500D03*
X636800Y262500D03*
X640300D03*
X640500Y302000D03*
X644000D03*
X640500Y322000D03*
X644000D03*
X640500Y327000D03*
X644000D03*
X640500Y337000D03*
X644000D03*
X640500Y332000D03*
X644000D03*
X640500Y317000D03*
X644000D03*
X640500Y307000D03*
X644000D03*
X640500Y312000D03*
X644000D03*
X625500Y469159D03*
X622000D03*
X616300Y466000D03*
X612800D03*
X615834Y469559D03*
X612334D03*
X616034Y472759D03*
X612534D03*
X625500D03*
X622000D03*
X632930Y492550D03*
X629430D03*
X625430D03*
X621930D03*
X655900Y587500D03*
X659400D03*
X659500Y591500D03*
X656000D03*
X683900Y21500D03*
X687400D03*
X673850Y27300D03*
X677350D03*
X687000Y14500D03*
X683500D03*
X687000Y11000D03*
X683500D03*
X696750Y31000D03*
X693250D03*
X679300Y30800D03*
X675800D03*
X686900Y17900D03*
X683400D03*
X679300Y34200D03*
X675800D03*
X667650Y34500D03*
X664150D03*
X698137Y69515D03*
X694637D03*
X696750Y34500D03*
X693250D03*
X688416Y69515D03*
X684916D03*
X718000Y203100D03*
X714500D03*
X714400Y207050D03*
X717900D03*
X722300Y218100D03*
X718800D03*
X697267Y200989D03*
X700767D03*
X684050Y278000D03*
X687550D03*
X687520Y257570D03*
X684020D03*
X687500Y251307D03*
X684000D03*
X703700Y258900D03*
X707200D03*
X688250Y264000D03*
X684750D03*
X684050Y260597D03*
X687550D03*
X707000Y262000D03*
X703500D03*
Y265500D03*
X707000D03*
X687550Y274500D03*
X684050D03*
X688250Y271000D03*
X684750D03*
X688250Y267500D03*
X684750D03*
X712300Y227500D03*
X715800D03*
X709000Y229000D03*
X705500D03*
X698000D03*
X701500D03*
X673713Y227609D03*
X670213D03*
X687500Y254470D03*
X684000D03*
X694000Y305500D03*
X690500D03*
X694000Y300500D03*
X690500D03*
X694000Y330500D03*
X690500D03*
X694000Y335500D03*
X690500D03*
X694000Y325500D03*
X690500D03*
X713050Y304375D03*
X709550D03*
X717300Y300700D03*
X720800D03*
X694000Y320500D03*
X690500D03*
X701000Y315500D03*
X697500D03*
X701000Y310500D03*
X697500D03*
X687556Y295292D03*
X684056D03*
X677124Y295168D03*
X680624D03*
X709550Y301275D03*
X713050D03*
X717300Y297500D03*
X720800D03*
X709550Y297975D03*
X713050D03*
X706662Y287275D03*
X710162D03*
X706662Y290775D03*
X710162D03*
X669200Y295000D03*
X665700D03*
X669000Y290200D03*
X665500D03*
X678772Y359140D03*
X682272D03*
X682150Y521600D03*
X678650D03*
X675250Y512500D03*
X671750D03*
X696750Y521000D03*
X693250D03*
X696750Y517000D03*
X693250D03*
X697500Y555750D03*
X694000D03*
X708155Y567556D03*
X704655D03*
X708153Y570862D03*
X704653D03*
X686500Y587800D03*
X690000D03*
X689500Y555750D03*
X686000D03*
X686500Y578500D03*
X683000D03*
X686599Y573493D03*
X683099D03*
X689950Y591000D03*
X686450D03*
X674380Y591560D03*
X677880D03*
X773500Y13078D03*
X770000D03*
X773500Y50878D03*
X770000D03*
X773500Y89000D03*
X770000D03*
X772732Y209533D03*
X776232D03*
X783732D03*
X780232D03*
X736000Y250500D03*
X739500D03*
X783115Y269655D03*
X779615D03*
X772519Y272931D03*
X776019D03*
X767000Y264400D03*
X763500D03*
X763232Y267610D03*
X766732D03*
X783485Y240623D03*
X779985D03*
X784358Y237423D03*
X780858D03*
X772351Y240966D03*
X775851D03*
X737000Y255000D03*
X733500D03*
X763250Y235500D03*
X766750D03*
X766800Y232000D03*
X763300D03*
X783045Y272906D03*
X779545D03*
X758917Y316392D03*
X762417D03*
X737750Y292500D03*
X741250D03*
X772870Y304000D03*
X776370D03*
X783211Y301964D03*
X779711D03*
X766900Y295800D03*
X763400D03*
X763232Y299033D03*
X766732D03*
X772732Y337533D03*
X776232D03*
X766250Y327608D03*
X762750D03*
X763200Y331900D03*
X766700D03*
X783286Y305173D03*
X779786D03*
X784765Y334046D03*
X781265D03*
X783732Y337533D03*
X780232D03*
X758952Y380738D03*
X762452D03*
X783194Y366012D03*
X779694D03*
X783182Y369533D03*
X779682D03*
X772982Y369033D03*
X776482D03*
X766800Y359800D03*
X763300D03*
X763232Y363033D03*
X766732D03*
X766300Y393400D03*
X762800D03*
X784486Y401784D03*
X780986D03*
X784520Y398509D03*
X781020D03*
X773400Y512800D03*
X769900D03*
X773100Y551400D03*
X769600D03*
X773300Y589200D03*
X769800D03*
X810700Y195600D03*
X807200D03*
X810700Y199100D03*
X807200D03*
X799850Y207600D03*
X803350D03*
X803100Y241000D03*
X806600D03*
X802100Y273000D03*
X805600D03*
X801300Y305000D03*
X804800D03*
X801800Y336400D03*
X805300D03*
X802208Y367560D03*
X805708D03*
X807000Y420000D03*
X803500D03*
X807000Y417000D03*
X803500D03*
X815500Y404000D03*
X812000D03*
X815500Y407500D03*
X812000D03*
X1081700Y268000D03*
X1078200D03*
X1105175Y277317D03*
X1101675D03*
X1107000Y302500D03*
X1110500D03*
Y284500D03*
X1107000D03*
X1110500Y295000D03*
X1107000D03*
X1110500Y299000D03*
X1107000D03*
X1110500Y288000D03*
X1107000D03*
X1110500Y291500D03*
X1107000D03*
X1106856Y281341D03*
X1110356D03*
X1109840Y322680D03*
X1106340D03*
X1267100Y134500D03*
X1270600D03*
X1274500Y138000D03*
X1278000D03*
Y141000D03*
X1274500D03*
X1255400Y113917D03*
X1251900D03*
X1255400Y116917D03*
X1251900D03*
Y110417D03*
X1255400D03*
X1251900Y120417D03*
X1255400D03*
X1278000Y134500D03*
X1274500D03*
X1267100Y138000D03*
X1270600D03*
X1246970Y137547D03*
X1250470D03*
X1254400Y125400D03*
X1250900D03*
X1268250Y461504D03*
X1271750D03*
X1275250D03*
X1271750D03*
X1277750Y482500D03*
Y479000D03*
Y474000D03*
Y487500D03*
X1268250Y466204D03*
X1271750D03*
X1275250D03*
X1271750D03*
X1274250Y474000D03*
X1277750D03*
X1274250Y479000D03*
X1277750D03*
X1274250Y482500D03*
X1277750D03*
X1274250Y487500D03*
X1277750D03*
X1258750Y490500D03*
X1262250D03*
X1265750D03*
X1262250D03*
X1258750Y485500D03*
X1262250D03*
X1265750D03*
X1262250D03*
X1260930Y474540D03*
X1264430D03*
X1260930Y469540D03*
X1264430D03*
X1267930Y474540D03*
X1264430D03*
X1267930Y469540D03*
X1264430D03*
X1340090Y7970D03*
X1330500Y80800D03*
X1334000D03*
X1340000Y86500D03*
X1336500D03*
X1334000Y77800D03*
X1330500D03*
X1334000Y68000D03*
X1330500D03*
X1334000Y55000D03*
X1330500D03*
Y64500D03*
X1334000D03*
X1330500Y61000D03*
X1334000D03*
X1317384Y81896D03*
X1313884D03*
X1319000Y95000D03*
X1315500D03*
X1325500D03*
X1322000D03*
X1332000Y95100D03*
X1328500D03*
X1336500Y83500D03*
X1340000D03*
X1334000Y74500D03*
X1330500D03*
X1334000Y71500D03*
X1330500D03*
X1334000Y58000D03*
X1330500D03*
X1333500Y40700D03*
X1330000D03*
X1330500Y51900D03*
X1334000D03*
X1341757Y96489D03*
X1340800Y413500D03*
X1337300D03*
X1342500Y419000D03*
X1314086Y462030D03*
X1310586D03*
X1307086D03*
X1310586D03*
X1332022Y464337D03*
X1335522D03*
X1339022D03*
X1335522D03*
X1338508Y510187D03*
X1335008D03*
X1330750Y501000D03*
X1327250D03*
X1307130Y466600D03*
X1310630D03*
X1314130D03*
X1310630D03*
X1332022Y469337D03*
X1335522D03*
X1281250Y482500D03*
Y479000D03*
Y474000D03*
Y487500D03*
X1339022Y469337D03*
X1335522D03*
X1324863Y477492D03*
X1328363D03*
X1324963Y472592D03*
X1328463D03*
X1331863Y477492D03*
X1328363D03*
X1331963Y472592D03*
X1328463D03*
X1341000Y540050D03*
X1343590Y7970D03*
X1372989Y8876D03*
X1369489D03*
X1363089Y8376D03*
X1366589D03*
X1362985Y11633D03*
X1366485D03*
X1381458Y-13901D03*
X1384958D03*
X1362273Y-20349D03*
X1365773D03*
X1386727Y4966D03*
X1383227D03*
X1382934Y-17458D03*
X1379434D03*
X1349944Y46449D03*
X1346444D03*
X1378000Y58500D03*
X1374500D03*
X1378000Y50500D03*
X1374500D03*
X1384300Y43900D03*
X1387800D03*
X1353040Y85780D03*
X1349540D03*
X1357000Y92340D03*
X1353500D03*
X1357000Y89140D03*
X1353500D03*
X1374400Y40200D03*
X1370900D03*
X1363400D03*
X1366900D03*
X1378000Y54500D03*
X1374500D03*
X1370820Y43895D03*
X1374320D03*
X1345257Y96489D03*
X1357700Y129450D03*
X1354200D03*
X1349700D03*
X1346200D03*
X1393200Y391745D03*
X1389700D03*
X1386100Y372776D03*
X1382600D03*
X1365000Y369139D03*
X1368500D03*
X1350800Y370500D03*
X1347300D03*
X1382933Y375976D03*
X1386433D03*
X1376200Y399100D03*
X1372700D03*
X1365707Y399068D03*
X1369207D03*
X1392200Y394845D03*
X1388700D03*
X1398280Y388701D03*
X1394780D03*
X1346000Y419000D03*
X1358000Y501800D03*
X1354500D03*
X1351700Y502200D03*
X1348200D03*
X1366500Y500500D03*
X1363000D03*
X1351700Y499000D03*
X1348200D03*
X1388986Y578365D03*
X1385486D03*
X1352500Y540050D03*
X1349000D03*
X1380420Y548730D03*
X1383920D03*
X1344500Y540050D03*
X1366484Y553447D03*
X1369984D03*
X1366534Y556907D03*
X1370034D03*
X1385317Y564894D03*
X1388817D03*
X1381685Y585222D03*
X1385185D03*
X1378400Y587056D03*
X1374900D03*
X1367400D03*
X1370900D03*
X1393735Y551044D03*
X1397235D03*
X1386250Y595500D03*
X1389750D03*
X1366791Y590313D03*
X1370291D03*
X1368200Y619200D03*
X1371700D03*
X1378200D03*
X1374700D03*
X1389750Y592000D03*
X1386250D03*
X1460631Y252416D03*
X1457131D03*
X1448839Y255160D03*
X1445339D03*
X1454500Y373000D03*
X1451000D03*
X1457569Y414166D03*
X1454069D03*
X1457569Y410666D03*
X1454069D03*
X1454500Y448000D03*
X1451000D03*
X1439000Y442500D03*
X1435500D03*
X1454500Y437000D03*
X1451000D03*
X1454500Y442500D03*
X1451000D03*
X1439000Y437000D03*
X1435500D03*
X1439000Y448000D03*
X1435500D03*
X1439000Y453500D03*
X1435500D03*
X1454500Y431500D03*
X1451000D03*
X1456100Y503000D03*
X1459600D03*
X1456100Y506000D03*
X1459600D03*
Y509000D03*
X1456100D03*
X1436060Y544955D03*
X1432560D03*
X1423140Y559233D03*
X1426640D03*
X1416272Y559180D03*
X1419772D03*
X1436000Y551500D03*
X1432500D03*
X1436100Y538400D03*
X1432600D03*
X1432560Y541455D03*
X1436060D03*
Y548455D03*
X1432560D03*
X1436100Y535400D03*
X1432600D03*
X1465400Y621700D03*
X1516600Y-6500D03*
X1520100D03*
X1525000D03*
X1512500D03*
X1509000D03*
X1489800Y115088D03*
X1493300D03*
X1489800Y120588D03*
X1493300D03*
X1489800Y115088D03*
X1486300D03*
X1492692Y127250D03*
X1489192D03*
X1489800Y120588D03*
X1486300D03*
X1492692Y127250D03*
X1496192D03*
X1492692Y132750D03*
X1489192D03*
X1492692D03*
X1496192D03*
X1520100Y200200D03*
X1516600D03*
X1492548Y215132D03*
X1489048D03*
X1507446Y221770D03*
X1503946D03*
X1524250Y314300D03*
X1520750D03*
X1523250Y338500D03*
X1519750D03*
X1511955Y310641D03*
X1508455D03*
X1511955Y307641D03*
X1508455D03*
X1512733Y295817D03*
X1509233D03*
X1503226Y623027D03*
X1506726D03*
X1474900Y622900D03*
X1478400D03*
X1468900Y621700D03*
X1576800Y-6800D03*
X1573300D03*
X1551300Y-6200D03*
X1547800D03*
X1554300D03*
X1557800D03*
X1589000Y-12600D03*
X1570300Y-6800D03*
X1566800D03*
X1577398Y-3069D03*
X1573898D03*
X1589000Y-16100D03*
X1528500Y-6500D03*
X1533000D03*
X1536500D03*
X1577398Y3931D03*
X1573898D03*
Y431D03*
X1577398D03*
X1584099Y146538D03*
X1580599D03*
X1584099Y143538D03*
X1580599D03*
X1585750Y149600D03*
X1582250D03*
X1573892Y134959D03*
X1570392D03*
X1585000Y135538D03*
X1581500D03*
X1581810Y132538D03*
X1585310D03*
X1581810Y129538D03*
X1585310D03*
X1575910Y120760D03*
X1579410D03*
X1570374Y140959D03*
X1573874D03*
Y143959D03*
X1570374D03*
X1570354Y137959D03*
X1573854D03*
X1578200Y215770D03*
X1581700D03*
X1578200Y210770D03*
X1581700D03*
X1588701Y172162D03*
X1585201D03*
X1588599Y169038D03*
X1585099D03*
X1588501Y161362D03*
X1585001D03*
X1588599Y164538D03*
X1585099D03*
X1585750Y189000D03*
X1582250D03*
X1585750Y194500D03*
X1582250D03*
X1571036Y159073D03*
X1574536D03*
X1549899Y255747D03*
X1546399D03*
X1557500Y260400D03*
X1561000D03*
X1546399Y252647D03*
X1549899D03*
X1528250Y314300D03*
X1531750D03*
X1557250Y298500D03*
X1553750D03*
X1557525Y308909D03*
X1554025D03*
X1557250Y305500D03*
X1553750D03*
X1557250Y301500D03*
X1553750D03*
X1583559Y321059D03*
X1587059D03*
X1528250Y317400D03*
X1531750D03*
X1536728Y322466D03*
X1533228D03*
X1557250Y312500D03*
X1553750D03*
X1566850Y344350D03*
X1570350D03*
X1566454Y620727D03*
X1569954D03*
X1557583Y620894D03*
X1561083D03*
X1541211Y604235D03*
X1537711D03*
X1539000Y610500D03*
X1542500D03*
X1575790Y597340D03*
X1579290D03*
X1575790Y601040D03*
X1579290D03*
X1534967Y616500D03*
X1531467D03*
X1538060Y598459D03*
X1541560D03*
X1530385Y620053D03*
X1533885D03*
X1592500Y-12600D03*
Y-16100D03*
X1608750Y90500D03*
X1605250D03*
X1627500Y72500D03*
X1624000D03*
X1621599Y90538D03*
X1618099D03*
X1627100Y197580D03*
X1623600D03*
X1602250Y197000D03*
X1598750D03*
X1614250D03*
X1610750D03*
X1645250Y252500D03*
X1641750D03*
X1641350Y231500D03*
X1644850D03*
X1641750Y255500D03*
X1645250D03*
X1604400Y242600D03*
X1600900D03*
X1605650Y246500D03*
X1602150D03*
Y249500D03*
X1605650D03*
Y252500D03*
X1602150D03*
X1615064Y222460D03*
X1618564D03*
X1605650Y255500D03*
X1602150D03*
X1618564Y225460D03*
X1615064D03*
X1644500Y325000D03*
X1641000D03*
Y328500D03*
X1644500D03*
X1594750Y402000D03*
X1598250D03*
X1638500Y398700D03*
X1635000D03*
X1620700Y391100D03*
X1617200D03*
X1645300Y361350D03*
X1648800D03*
X1645300Y364850D03*
X1648800D03*
X1601829Y379923D03*
X1605329D03*
X1601829Y376723D03*
X1605329D03*
X1623750Y446500D03*
X1627250D03*
X1609250Y451000D03*
X1605750D03*
X1605669Y454809D03*
X1609169D03*
X1627300Y439500D03*
X1623800D03*
X1616300Y450000D03*
X1612800D03*
X1615300Y459100D03*
X1611800D03*
X1605750Y446000D03*
X1609250D03*
X1633250Y449500D03*
X1636750D03*
X1627300Y453663D03*
X1623800D03*
X1636700Y445800D03*
X1633200D03*
X1633250Y452500D03*
X1636750D03*
X1623750Y443500D03*
X1627250D03*
X1635700Y441900D03*
X1632200D03*
X1614750Y442500D03*
X1618250D03*
X1614750Y439500D03*
X1618250D03*
X1594000Y455500D03*
X1590500D03*
X1597800Y408400D03*
X1601300D03*
X1601250Y416000D03*
X1597750D03*
X1597800Y412000D03*
X1601300D03*
X1609250Y426000D03*
X1605750D03*
X1627250Y432000D03*
X1623750D03*
X1627250Y435500D03*
X1623750D03*
X1633250D03*
X1636750D03*
Y432000D03*
X1633250D03*
X1605750Y432500D03*
X1609250D03*
X1605750Y435500D03*
X1609250D03*
Y429000D03*
X1605750D03*
X1614750Y432500D03*
X1618250D03*
X1614750Y429000D03*
X1618250D03*
X1614750Y435500D03*
X1618250D03*
X1614750Y426000D03*
X1618250D03*
X1605449Y422971D03*
X1608949D03*
X1606250Y416000D03*
X1609750D03*
Y412000D03*
X1606250D03*
X1615250Y415500D03*
X1618750D03*
X1620847Y418837D03*
X1617347D03*
X1620847Y421837D03*
X1617347D03*
X1627300Y449800D03*
X1623800D03*
X1605260Y442230D03*
X1608760D03*
X1593600Y491500D03*
X1590100D03*
X1593500Y487300D03*
X1590000D03*
X1615898Y495476D03*
X1619398D03*
X1615898Y492476D03*
X1619398D03*
X1623361Y521918D03*
X1619861D03*
X1623361Y518918D03*
X1619861D03*
X1611057Y465508D03*
X1607557D03*
X1608813Y483559D03*
X1605313D03*
X1608813Y480359D03*
X1605313D03*
X1611057Y468708D03*
X1607557D03*
X1603957Y476708D03*
X1600457D03*
X1603957Y473508D03*
X1600457D03*
X1599104Y580396D03*
X1595604D03*
Y588396D03*
X1599104D03*
Y584396D03*
X1595604D03*
X1599104Y592396D03*
X1595604D03*
X1704900Y63200D03*
X1708400D03*
X1686000Y90000D03*
X1682500D03*
X1689000D03*
X1692500D03*
X1704900Y72968D03*
X1708400D03*
X1684020Y142025D03*
X1687520D03*
X1654819Y212708D03*
X1651319D03*
X1696368Y177380D03*
X1699868D03*
X1693343Y177381D03*
X1689843D03*
X1696400Y174350D03*
X1699900D03*
X1706620Y172616D03*
X1710120D03*
X1693242Y198749D03*
X1696742D03*
X1703242D03*
X1699742D03*
X1659050Y410500D03*
X1662550D03*
X1655550Y413500D03*
X1652050D03*
X1655550Y410500D03*
X1652050D03*
X1659050Y413500D03*
X1662550D03*
X1655250Y445000D03*
X1651750D03*
X1658750D03*
X1662250D03*
X1675650Y494800D03*
X1679150D03*
X1675450Y491800D03*
X1678950D03*
X1675350Y488400D03*
X1678850D03*
X1675750Y511000D03*
X1679250D03*
X1675750Y514000D03*
X1679250D03*
X1675750Y498050D03*
X1679250D03*
X1675750Y501250D03*
X1679250D03*
X1675750Y504550D03*
X1679250D03*
X1695802Y502313D03*
X1699302D03*
X1716163Y3233D03*
X1719663D03*
X1756250Y4500D03*
X1752750D03*
X1745250D03*
X1748750D03*
X1729750Y63500D03*
X1726250D03*
X1723250D03*
X1719750D03*
X1729750Y60500D03*
X1726250D03*
X1723250D03*
X1719750D03*
Y57500D03*
X1723250D03*
X1719750Y66500D03*
X1723250D03*
X1748594Y49606D03*
X1745094D03*
Y55606D03*
X1741594D03*
X1745094Y52606D03*
X1741594D03*
X1762500Y63000D03*
X1759000D03*
X1769000Y83500D03*
X1772500D03*
X1771000Y79800D03*
X1774500D03*
X1719450Y86600D03*
X1722950D03*
X1764529Y111540D03*
X1761029D03*
X1764850Y158650D03*
X1761350D03*
X1739000Y566000D03*
X1735500D03*
X1739000Y563000D03*
X1735500D03*
X1736000Y554000D03*
X1732500D03*
X1745250Y577100D03*
X1748750D03*
X1737814Y581186D03*
X1741314D03*
X1765180Y604490D03*
X1761680D03*
X1833600Y-15700D03*
X1828500Y1000D03*
X1832000D03*
X1808000Y6000D03*
X1811500D03*
X1819000D03*
X1815500D03*
X1795696Y6061D03*
X1792196D03*
X1835500Y800D03*
X1833050Y94550D03*
X1829550D03*
X1833050Y90850D03*
X1829550D03*
X1829500Y87500D03*
X1833000D03*
X1829550Y97850D03*
X1833050D03*
X1807348Y151937D03*
X1803848D03*
X1802750Y120000D03*
X1799250D03*
X1790250D03*
X1793750D03*
X1833023Y101490D03*
X1833047Y104556D03*
X1788250Y126500D03*
X1784750D03*
X1792750Y101800D03*
X1796250D03*
X1833280Y570500D03*
X1776500Y604500D03*
X1780000D03*
X1837100Y-15700D03*
X1889594Y-15042D03*
X1893094D03*
X1889581Y-18335D03*
X1893081D03*
X1839000Y800D03*
X1896581Y-18335D03*
X1893081D03*
X1896594Y-15042D03*
X1893094D03*
X1843500Y81300D03*
X1847000D03*
X1880536Y57002D03*
X1884036D03*
X1880536Y60047D03*
X1884036D03*
X1840250Y81300D03*
X1836750D03*
X1863000Y117500D03*
X1859500D03*
X1863000Y120500D03*
X1859500D03*
X1892370Y140100D03*
X1888870D03*
X1836523Y101490D03*
X1836547Y104556D03*
X1879150Y169100D03*
X1882650D03*
Y166100D03*
X1879150D03*
X1882650Y162600D03*
X1879150D03*
Y159100D03*
X1882650D03*
X1853150Y169600D03*
X1856650D03*
X1880750Y562500D03*
X1884250D03*
X1864750Y545000D03*
X1861250D03*
X1864750Y549500D03*
X1861250D03*
X1836780Y570500D03*
X1896450Y539500D03*
X1891750Y562500D03*
X1888250D03*
X1861961Y557512D03*
X1865461D03*
X1872350Y580350D03*
X1875850D03*
X1957169Y81509D03*
X1931500Y153600D03*
X1935000D03*
X1921800Y137300D03*
X1925300D03*
X1922000Y132500D03*
X1925500D03*
X1906590Y110820D03*
X1903090D03*
X1903790Y115280D03*
X1900290D03*
X1903790Y119280D03*
X1900290D03*
X1946190Y101730D03*
X1949690D03*
X1935450Y196100D03*
X1931950D03*
X1936750Y173600D03*
X1933250D03*
X1930150Y190100D03*
X1933650D03*
Y181100D03*
X1930150D03*
X1933650Y184100D03*
X1930150D03*
X1936750Y165600D03*
X1933250D03*
X1936750Y169600D03*
X1933250D03*
X1936750Y161600D03*
X1933250D03*
X1936750Y157600D03*
X1933250D03*
X1949110Y489180D03*
X1945610D03*
X1929480Y475430D03*
X1925980D03*
X1949050Y492280D03*
X1945550D03*
X1916390Y483910D03*
X1912890D03*
X1916460Y487390D03*
X1912960D03*
X1930250Y566442D03*
X1926750D03*
X1930250Y569442D03*
X1926750D03*
X1917744Y540400D03*
X1921244D03*
X1899950Y539500D03*
X1926750Y572942D03*
X1930250D03*
X1931239Y596040D03*
X1934739D03*
X1931249Y599040D03*
X1934749D03*
X1934699Y605040D03*
X1931199D03*
X1934699Y602040D03*
X1931199D03*
X1929600Y590100D03*
X1926100D03*
X1927015Y611391D03*
X1930515D03*
X1963271Y93138D03*
X1959771D03*
X1960669Y81509D03*
G54D128*
X678800Y228100D03*
X1337472Y40715D03*
X1351360Y9620D03*
X1355200Y368200D03*
X1351600Y556000D03*
X1356882Y618600D03*
G54D254*
X1741609Y167494D03*
G54D80*
X64605Y307250D03*
X66575D03*
X68545D03*
X70515D03*
X72485D03*
X74455D03*
X76425D03*
X78395D03*
G54D290*
X1851250Y561000D03*
G54D182*
X1462000Y-5000D03*
Y-15000D03*
X1452000Y-5000D03*
Y-15000D03*
X1442000Y-5000D03*
X1525000Y-15000D03*
X1515000D03*
X1482000D03*
X1472000Y-5000D03*
Y-15000D03*
X1492000Y-5000D03*
Y-15000D03*
X1482000Y-5000D03*
X1575000Y-15000D03*
X1565000D03*
X1555000D03*
X1545000D03*
X1535000D03*
X1713503Y-5000D03*
Y-15000D03*
X1703503Y-5000D03*
X1743503Y-15000D03*
X1733503Y-5000D03*
Y-15000D03*
X1723503Y-5000D03*
Y-15000D03*
X1753503Y-5000D03*
Y-15000D03*
X1743503Y-5000D03*
X1769504D03*
X1809504Y-15000D03*
X1799504Y-5000D03*
Y-15000D03*
X1789504Y-5000D03*
Y-15000D03*
X1779504Y-5000D03*
Y-15000D03*
X1819504Y-5000D03*
Y-15000D03*
X1809504Y-5000D03*
G54D209*
X1527500Y490177D03*
Y493445D03*
X1496004Y490177D03*
X1499941D03*
X1503878D03*
X1507815D03*
X1511752D03*
Y493445D03*
X1515689Y490177D03*
X1519626D03*
X1523563D03*
X1525531Y491811D03*
Y495079D03*
X1507815Y493445D03*
X1488130Y490177D03*
Y493445D03*
X1490098Y491811D03*
Y495079D03*
X1492067Y490177D03*
X1509783Y495079D03*
Y491811D03*
X1486161D03*
X1517657Y495079D03*
Y491811D03*
X1519626Y493445D03*
X1521594Y495079D03*
Y491811D03*
X1523563Y493445D03*
X1492067D03*
X1494035Y495079D03*
Y491811D03*
X1496004Y493445D03*
X1497972Y495079D03*
Y491811D03*
X1499941Y493445D03*
X1501909Y495079D03*
Y491811D03*
X1503878Y493445D03*
X1505846Y495079D03*
Y491811D03*
X1513720Y495079D03*
Y491811D03*
X1515689Y493445D03*
X1562933Y490177D03*
Y493445D03*
X1564902Y491811D03*
Y495079D03*
X1555059Y490177D03*
X1558996D03*
X1531437D03*
X1535374D03*
Y493445D03*
X1539311Y490177D03*
X1543248D03*
X1547185D03*
Y493445D03*
X1549154Y491811D03*
Y495079D03*
X1551122Y490177D03*
X1568839Y491811D03*
X1537343D03*
Y495079D03*
X1541280Y491811D03*
Y495079D03*
X1543248Y493445D03*
X1545217Y491811D03*
Y495079D03*
X1539311Y493445D03*
X1533406Y495079D03*
Y491811D03*
X1529469Y495079D03*
Y491811D03*
X1531437Y493445D03*
X1551122D03*
X1553091Y491811D03*
Y495079D03*
X1555059Y493445D03*
X1557028Y491811D03*
Y495079D03*
X1558996Y493445D03*
X1560965Y491811D03*
Y495079D03*
X1566870Y493445D03*
Y490177D03*
G54D164*
X1248059Y474441D03*
X1244243Y470374D03*
G54D62*
X63261Y8225D03*
X117589Y227500D03*
X110032Y373284D03*
X680330Y9287D03*
X767277Y323658D03*
X1307363Y480350D03*
X1310700Y492569D03*
X1345561Y84900D03*
X1384906Y394845D03*
X1349779Y479400D03*
X1400050Y501950D03*
X1442800Y439175D03*
X1443000Y450275D03*
X1447800Y440125D03*
X1448000Y451225D03*
X1444550Y412364D03*
X1449350Y411414D03*
X1421608Y485300D03*
X1426993Y486250D03*
X1780543Y609000D03*
X1850407Y93219D03*
X1836531Y97664D03*
X1929336Y167130D03*
G54D263*
X1727112Y600844D03*
X1733096D03*
X1891736Y190300D03*
X1895673D03*
X1893705D03*
X1897642D03*
X1901579D03*
X1913390D03*
X1915359D03*
X1921264D03*
X1907485D03*
X1909453D03*
X1903548D03*
X1905516D03*
X1911422D03*
X1919296D03*
X1917327D03*
X1899611D03*
G54D192*
X1417111Y466941D03*
G54D27*
X24054Y21862D03*
X24143Y52374D03*
X19400Y562500D03*
X14700Y529100D03*
X138100Y208300D03*
X141900Y272900D03*
X138100Y241000D03*
X138800Y306100D03*
X140609Y337400D03*
X138410Y369674D03*
X786982Y368417D03*
X790099Y207600D03*
X793551Y240966D03*
X792787Y272898D03*
X790200Y336400D03*
X791970Y305000D03*
G54D147*
X1236150Y300592D03*
G54D282*
X1888390Y109250D03*
X1874600D03*
X1882480D03*
X1880510D03*
X1890360D03*
X1872630D03*
X1876570D03*
X1878540D03*
X1884450D03*
X1886420D03*
G54D90*
X103191Y452592D03*
Y471458D03*
G54D174*
X1287176Y385127D03*
X1290105Y374700D03*
G54D45*
X44291Y178386D03*
G54D129*
X715095Y244080D03*
Y236480D03*
X723604Y237024D03*
Y229424D03*
X693061Y228414D03*
Y236014D03*
X732344Y237043D03*
Y229443D03*
X741055Y241836D03*
Y234236D03*
X1384771Y79997D03*
Y87597D03*
X1376912Y79978D03*
Y87578D03*
X1372000Y414300D03*
Y406700D03*
X1364000Y414300D03*
Y406700D03*
X1441554Y578539D03*
Y586139D03*
X1456514Y618961D03*
Y611361D03*
X1448514Y618961D03*
Y611361D03*
X1440514Y618961D03*
Y611361D03*
X1519200Y253300D03*
Y260900D03*
X1526900Y253300D03*
Y260900D03*
X1520650Y275000D03*
Y267400D03*
X1528450Y275000D03*
Y267400D03*
X1603940Y223735D03*
Y231335D03*
X1596340Y223735D03*
Y231335D03*
X1874141Y84412D03*
Y92012D03*
X1881900Y84400D03*
Y92000D03*
X1896900Y79500D03*
Y87100D03*
X1861670Y110400D03*
Y102800D03*
X1929718Y216175D03*
X1938491Y216142D03*
X1929718Y223775D03*
X1938491Y223742D03*
X1938900Y239800D03*
Y232200D03*
X1930600Y239800D03*
Y232200D03*
G54D165*
X1239722Y474778D03*
X1232141Y467872D03*
G54D273*
X1843825Y86900D03*
X1842250D03*
X1840675D03*
G54D138*
X1267805Y253386D03*
G54D309*
X1965132Y477599D03*
X1973450D03*
X1965132Y506339D03*
X1973450D03*
G54D54*
X34126Y519000D03*
X47874D03*
X1393388Y86754D03*
X1395515Y405921D03*
X1381767D03*
X1407136Y86754D03*
G54D246*
X1604323Y469147D03*
G54D156*
X1262771Y355220D03*
G54D18*
X-15831Y547265D03*
X-15361Y583807D03*
X4400Y71700D03*
X-1100D03*
X-10331Y547265D03*
X-9861Y583807D03*
X47070Y607000D03*
X69652Y4240D03*
X75152D03*
X108500Y259500D03*
Y227500D03*
X107966Y290332D03*
X108200Y322500D03*
X52570Y607000D03*
X168200Y207870D03*
X114000Y259500D03*
Y227500D03*
X113466Y290332D03*
X113700Y322500D03*
X116250Y356500D03*
X110750D03*
X116120Y388180D03*
X110620D03*
X173700Y207870D03*
X179150Y202100D03*
X173650D03*
X386048Y275141D03*
X391548D03*
X386056Y270241D03*
X391556D03*
X599000Y13000D03*
Y51000D03*
X598950Y89550D03*
X598900Y513200D03*
X598800Y551200D03*
Y589000D03*
X616500Y13000D03*
X611000D03*
X604500D03*
X660112Y39650D03*
X654612D03*
X616900Y51000D03*
X611400D03*
X616150Y89550D03*
X610650D03*
X604500Y51000D03*
X604450Y89550D03*
X643300Y295200D03*
X637800D03*
X615900Y513200D03*
X610400D03*
X604400D03*
X618000Y589000D03*
X612500D03*
X618500Y551200D03*
X613000D03*
X604300D03*
Y589000D03*
X720596Y84030D03*
X726096D03*
X675972Y40376D03*
X681472D03*
X671261Y40403D03*
X665761D03*
X718000Y211000D03*
X723500D03*
X677600Y526000D03*
X683100D03*
X672895Y526398D03*
X667395D03*
X689680Y582490D03*
X684180D03*
X670700Y569400D03*
X665200D03*
X763500Y228000D03*
X758000D03*
X764500Y260105D03*
X759000D03*
X763950Y323658D03*
X758450D03*
X761700Y292000D03*
X756200D03*
X763875Y355850D03*
X758375D03*
X765400Y388700D03*
X759900D03*
X818500Y207870D03*
X824000D03*
X1035656Y270241D03*
X1041156D03*
X1035656Y275141D03*
X1041156D03*
X1248608Y13000D03*
X1254108D03*
X1266108D03*
X1260608D03*
X1248608Y51000D03*
X1254108D03*
X1266508D03*
X1261008D03*
X1248608Y89528D03*
X1254108D03*
X1266108D03*
X1260608D03*
X1249000Y513200D03*
X1254500D03*
X1265500D03*
X1260000D03*
X1248608Y552000D03*
X1254108D03*
X1266508D03*
X1261008D03*
X1248608Y590000D03*
X1254108D03*
X1266108D03*
X1260608D03*
X1319200Y99450D03*
X1313700D03*
X1337134Y99469D03*
X1331634D03*
X1341700Y409200D03*
X1336200D03*
X1341700Y404300D03*
X1336200D03*
X1330342Y513603D03*
X1324842D03*
X1382247Y-9885D03*
X1387747D03*
X1385946Y379926D03*
X1391446D03*
X1385116Y568907D03*
X1390616D03*
X1385250Y599500D03*
X1390750D03*
X1444047Y402785D03*
X1449547D03*
X1507300Y552900D03*
X1501800D03*
X1507300Y558050D03*
X1501800D03*
X1515829Y556974D03*
X1521329D03*
X1515970Y551760D03*
X1521470D03*
X1485000Y622600D03*
X1490500D03*
X1521094Y622646D03*
X1526594D03*
X1559545Y274225D03*
X1554045D03*
X1585170Y571204D03*
X1558950Y578800D03*
X1553450D03*
X1606500Y371948D03*
X1601000D03*
X1606500Y367248D03*
X1601000D03*
X1600750Y460500D03*
X1595250D03*
X1600750Y465500D03*
X1595250D03*
X1624000Y502200D03*
X1618500D03*
X1590670Y571204D03*
X1596004Y601196D03*
X1590504D03*
X1765753Y115662D03*
X1760253D03*
X1784500Y105700D03*
X1779000D03*
X1791750Y97800D03*
X1797250D03*
X1836630Y138000D03*
X1797348Y166937D03*
X1802848D03*
X1842130Y138000D03*
X1887100Y546100D03*
X1881600D03*
G54D36*
X8141Y29503D03*
Y31275D03*
X8466Y60870D03*
Y62642D03*
Y64413D03*
Y66185D03*
Y67957D03*
Y69728D03*
Y71500D03*
Y73272D03*
Y75043D03*
Y76815D03*
X8141Y33046D03*
Y34818D03*
Y36590D03*
Y38361D03*
Y40133D03*
Y41905D03*
Y43676D03*
Y45448D03*
X-1959Y536159D03*
Y537931D03*
Y539702D03*
Y541474D03*
Y543246D03*
Y545017D03*
Y546789D03*
Y548561D03*
Y550332D03*
Y552104D03*
Y572159D03*
Y573931D03*
Y575702D03*
Y577474D03*
Y579246D03*
Y581017D03*
Y582789D03*
Y584561D03*
Y586332D03*
Y588104D03*
X122165Y216692D03*
Y248692D03*
Y250464D03*
Y252235D03*
Y254007D03*
Y255779D03*
Y257550D03*
Y259322D03*
Y261094D03*
Y262865D03*
Y264637D03*
Y218464D03*
Y220235D03*
Y222007D03*
Y223779D03*
Y225550D03*
Y227322D03*
Y229094D03*
Y230865D03*
Y232637D03*
Y280692D03*
Y282464D03*
Y284235D03*
Y286007D03*
Y287779D03*
Y289550D03*
Y291322D03*
Y293094D03*
Y294865D03*
Y296637D03*
Y312692D03*
Y314464D03*
Y316235D03*
Y318007D03*
Y319779D03*
Y321550D03*
Y323322D03*
Y325094D03*
Y326865D03*
Y328637D03*
Y344692D03*
Y346464D03*
Y348235D03*
Y350007D03*
Y351779D03*
Y353550D03*
Y355322D03*
Y357094D03*
Y358865D03*
Y360637D03*
Y376692D03*
Y378464D03*
Y380235D03*
Y382007D03*
Y383779D03*
Y385550D03*
Y387322D03*
Y389094D03*
Y390865D03*
Y392637D03*
X709959Y216526D03*
Y214754D03*
Y212983D03*
Y211211D03*
Y209439D03*
Y207668D03*
Y205896D03*
Y221841D03*
Y220069D03*
Y218298D03*
X771773Y216692D03*
Y218464D03*
Y220235D03*
Y222007D03*
Y223779D03*
Y225550D03*
Y227322D03*
Y229094D03*
Y230865D03*
Y232637D03*
Y248692D03*
Y250464D03*
Y252235D03*
Y254007D03*
Y255779D03*
Y257550D03*
Y259322D03*
Y261094D03*
Y262865D03*
Y264637D03*
Y312692D03*
Y314464D03*
Y316235D03*
Y318007D03*
Y319779D03*
Y321550D03*
Y323322D03*
Y325094D03*
Y326865D03*
Y328637D03*
Y280692D03*
Y282464D03*
Y284235D03*
Y286007D03*
Y287779D03*
Y289550D03*
Y291322D03*
Y293094D03*
Y294865D03*
Y296637D03*
Y344692D03*
Y346464D03*
Y348235D03*
Y350007D03*
Y351779D03*
Y353550D03*
Y355322D03*
Y357094D03*
Y358865D03*
Y360637D03*
X771723Y376692D03*
Y378464D03*
Y380235D03*
Y382007D03*
Y383779D03*
Y385550D03*
Y387322D03*
Y389094D03*
Y390865D03*
Y392637D03*
X1375048Y1017D03*
Y-755D03*
Y-2526D03*
Y-4298D03*
Y-6070D03*
Y-7841D03*
Y-9613D03*
Y-11385D03*
Y-13156D03*
Y-14928D03*
X1375359Y31269D03*
Y29498D03*
Y27726D03*
Y25954D03*
Y24183D03*
Y22411D03*
Y20639D03*
Y18868D03*
Y17096D03*
Y33041D03*
X1377666Y391909D03*
Y390137D03*
Y388366D03*
Y386594D03*
Y384822D03*
Y383051D03*
Y381279D03*
Y379507D03*
Y377736D03*
Y375964D03*
X1379359Y579897D03*
Y578125D03*
Y576354D03*
Y574582D03*
Y572810D03*
Y571039D03*
Y569267D03*
Y567495D03*
Y565724D03*
Y563952D03*
Y611097D03*
Y609325D03*
Y607554D03*
Y605782D03*
Y604010D03*
Y602239D03*
Y600467D03*
Y598695D03*
Y596924D03*
Y595152D03*
G54D72*
X84419Y327900D03*
X82450Y332500D03*
X86387Y327900D03*
Y332500D03*
X84419D03*
G54D219*
X1586547Y-6702D03*
X1592531D03*
G54D228*
X1546953Y273250D03*
Y259750D03*
X1541047D03*
Y273250D03*
G54D255*
X1741609Y173094D03*
G54D237*
X1623812Y268699D03*
G54D81*
X80750Y304895D03*
Y302925D03*
Y300955D03*
Y298985D03*
Y297015D03*
Y295045D03*
Y293075D03*
Y291105D03*
G54D183*
X1442000Y-15000D03*
X1505000D03*
X1703503D03*
X1769504D03*
G54D63*
X107249Y105000D03*
X102328D03*
X97406D03*
X92485D03*
X87564D03*
X82643D03*
X77721D03*
G54D264*
X1736245Y594742D03*
Y598679D03*
Y596711D03*
Y592773D03*
Y590805D03*
X1923700Y176053D03*
Y178021D03*
Y187864D03*
Y183927D03*
Y181958D03*
Y179990D03*
Y185895D03*
Y170147D03*
Y172116D03*
Y174084D03*
Y166210D03*
Y168179D03*
Y162273D03*
Y160305D03*
Y158336D03*
Y164242D03*
G54D291*
X1938249Y80902D03*
G54D148*
X1269395Y310026D03*
G54D265*
X1808600Y48200D03*
Y73000D03*
X1786800Y48200D03*
Y73000D03*
G54D166*
X1225284Y468813D03*
X1234100Y475081D03*
G54D139*
X1254526Y258759D03*
G54D55*
X17750Y510887D03*
Y509312D03*
Y507737D03*
Y506162D03*
Y504587D03*
Y503013D03*
Y501438D03*
Y499863D03*
Y498288D03*
Y496713D03*
X675750Y270087D03*
Y268512D03*
Y266937D03*
Y265362D03*
Y263787D03*
Y262213D03*
Y260638D03*
Y259063D03*
Y257488D03*
Y255913D03*
X1366650Y67587D03*
Y66012D03*
Y64437D03*
Y62862D03*
Y61287D03*
Y59713D03*
Y58138D03*
Y56563D03*
Y54988D03*
Y53413D03*
G54D229*
X1576634Y397067D03*
X1573366Y389193D03*
Y385256D03*
Y393130D03*
Y397067D03*
Y401004D03*
Y381319D03*
X1576634Y393130D03*
X1575000Y391161D03*
X1578268Y387224D03*
X1575000D03*
X1576634Y389193D03*
X1578268Y391161D03*
Y383287D03*
X1575000D03*
X1576634Y381319D03*
Y385256D03*
X1575000Y379350D03*
X1578268Y402972D03*
X1576634Y401004D03*
X1575000Y402972D03*
Y399035D03*
X1578268D03*
Y395098D03*
X1575000D03*
X1576634Y412815D03*
Y460059D03*
X1578268Y438406D03*
Y454154D03*
X1575000D03*
X1573366Y404941D03*
Y408878D03*
Y412815D03*
Y416752D03*
Y420689D03*
Y424626D03*
Y428563D03*
Y432500D03*
Y436437D03*
Y440374D03*
Y444311D03*
Y448248D03*
Y452185D03*
Y456122D03*
Y460059D03*
Y463996D03*
X1575000Y438406D03*
X1576634Y404941D03*
X1575000Y406909D03*
X1576634Y408878D03*
X1578268Y406909D03*
X1575000Y410846D03*
X1578268D03*
Y442343D03*
X1576634Y440374D03*
Y448248D03*
X1575000Y446280D03*
X1576634Y452185D03*
X1575000Y442343D03*
X1576634Y444311D03*
X1578268Y446280D03*
Y450217D03*
X1575000D03*
X1578268Y418720D03*
X1576634Y424626D03*
X1575000Y430531D03*
X1576634Y428563D03*
Y420689D03*
X1575000Y418720D03*
X1578268Y414783D03*
Y426594D03*
X1575000Y414783D03*
X1576634Y436437D03*
X1578268Y430531D03*
Y422657D03*
X1576634Y432500D03*
X1578268Y434469D03*
X1575000D03*
Y426594D03*
Y422657D03*
X1576634Y416752D03*
X1575000Y462028D03*
X1576634Y463996D03*
X1578268Y462028D03*
X1575000Y458091D03*
X1578268D03*
X1576634Y456122D03*
X1573366Y467933D03*
Y471870D03*
Y475807D03*
Y479744D03*
X1575000Y465965D03*
Y481713D03*
X1576634Y467933D03*
Y479744D03*
X1575000Y469902D03*
Y477776D03*
X1576634Y471870D03*
Y475807D03*
X1575000Y485650D03*
X1573366Y483681D03*
X1575000Y473839D03*
X1578268Y465965D03*
Y481713D03*
Y469902D03*
Y477776D03*
X1576634Y483681D03*
X1578268Y473839D03*
G54D157*
X1270621Y355590D03*
G54D238*
X1632112Y252087D03*
Y256024D03*
Y259961D03*
X1615512Y242244D03*
Y246181D03*
Y250118D03*
Y254055D03*
Y257992D03*
X1632112Y244213D03*
Y248150D03*
X1615512Y261929D03*
G54D292*
X1943369Y80902D03*
G54D256*
X1766145Y460603D03*
X1769295Y441754D03*
Y460603D03*
X1772445Y441754D03*
Y460603D03*
X1734649Y441754D03*
Y460603D03*
X1737799Y441754D03*
Y460603D03*
X1740948Y441754D03*
Y460603D03*
X1744098Y441754D03*
Y460603D03*
X1747248Y441754D03*
Y460603D03*
X1750397Y441754D03*
Y460603D03*
X1753547Y441754D03*
Y460603D03*
X1756696Y441754D03*
Y460603D03*
X1759846Y441754D03*
Y460603D03*
X1762996Y441754D03*
Y460603D03*
X1766145Y441754D03*
X1775594D03*
Y460603D03*
X1778744Y441754D03*
Y460603D03*
X1781893Y441754D03*
Y460603D03*
X1785043Y441754D03*
Y460603D03*
X1788193Y441754D03*
Y460603D03*
X1791342Y441754D03*
Y460603D03*
X1794492Y441754D03*
Y460603D03*
X1797641Y441754D03*
Y460603D03*
X1800791Y441754D03*
Y460603D03*
X1803941Y441754D03*
Y460603D03*
X1807090Y441754D03*
Y460603D03*
X1810240Y441754D03*
Y460603D03*
X1813389Y441754D03*
Y460603D03*
X1816539Y441754D03*
Y460603D03*
X1819689Y441754D03*
Y460603D03*
X1822838Y441754D03*
Y460603D03*
X1825988Y441754D03*
Y460603D03*
X1829137Y441754D03*
Y460603D03*
X1832287Y441754D03*
Y460603D03*
X1835437Y441754D03*
Y460603D03*
X1838586Y441754D03*
Y460603D03*
X1841736Y441754D03*
Y460603D03*
X1844885Y441754D03*
Y460603D03*
X1848035Y441754D03*
Y460603D03*
X1851185Y441754D03*
Y460603D03*
X1854334Y441754D03*
Y460603D03*
X1857484Y441754D03*
Y460603D03*
X1860633Y441754D03*
Y460603D03*
X1863783Y441754D03*
Y460603D03*
X1866933Y441754D03*
Y460603D03*
X1870082Y441754D03*
Y460603D03*
X1873232Y441754D03*
Y460603D03*
X1876382Y441754D03*
Y460603D03*
X1879531Y441754D03*
Y460603D03*
X1882681Y441754D03*
Y460603D03*
X1885830Y441754D03*
Y460603D03*
X1888980Y441754D03*
Y460603D03*
X1892130Y441754D03*
Y460603D03*
X1895279Y441754D03*
Y460603D03*
X1907878D03*
X1911027Y441754D03*
Y460603D03*
X1914177Y441754D03*
Y460603D03*
X1917326Y441754D03*
Y460603D03*
X1920476Y441754D03*
X1898429D03*
Y460603D03*
X1901578Y441754D03*
Y460603D03*
X1904728Y441754D03*
Y460603D03*
X1907878Y441754D03*
X1920476Y460603D03*
G54D184*
X1407422Y17283D03*
Y30669D03*
X1410571Y17283D03*
Y30669D03*
X1413721Y17283D03*
Y30669D03*
X1416871Y17283D03*
Y30669D03*
X1420020Y17283D03*
Y30669D03*
X1423170Y17283D03*
Y30669D03*
X1426319Y17283D03*
Y30669D03*
X1429469Y17283D03*
Y30669D03*
X1432619Y17283D03*
Y30669D03*
X1435768Y17283D03*
Y30669D03*
X1438918Y17283D03*
Y30669D03*
X1442067Y17283D03*
Y30669D03*
X1445217Y17283D03*
Y30669D03*
X1448367Y17283D03*
Y30669D03*
X1451516Y17283D03*
Y30669D03*
X1454666Y17283D03*
Y30669D03*
X1457815Y17283D03*
Y30669D03*
X1460965Y17283D03*
Y30669D03*
X1464115Y17283D03*
Y30669D03*
X1486162D03*
X1489311Y17283D03*
Y30669D03*
X1492461Y17283D03*
Y30669D03*
X1495611Y17283D03*
Y30669D03*
X1467264Y17283D03*
Y30669D03*
X1470414Y17283D03*
X1498760D03*
X1470414Y30669D03*
X1473563Y17283D03*
Y30669D03*
X1476713Y17283D03*
Y30669D03*
X1479863Y17283D03*
Y30669D03*
X1483012Y17283D03*
Y30669D03*
X1486162Y17283D03*
X1498760Y30669D03*
G54D283*
X1882548Y174684D03*
X1903566Y146090D03*
G54D73*
X82450Y328000D03*
G54D37*
X19421Y27947D03*
X17649D03*
X15878D03*
X14106D03*
X12334D03*
X10563D03*
X19746Y59314D03*
X17974D03*
X16203D03*
X14431D03*
X12659D03*
X10888D03*
X9321Y534603D03*
X7549D03*
X5778D03*
X4006D03*
X2234D03*
X463D03*
X9321Y570603D03*
X7549D03*
X5778D03*
X4006D03*
X2234D03*
X463D03*
X133445Y215136D03*
X131673D03*
X129902D03*
X128130D03*
X126358D03*
X124587D03*
X133445Y279136D03*
X131673D03*
X129902D03*
X128130D03*
X126358D03*
X124587D03*
X133445Y247136D03*
X131673D03*
X129902D03*
X128130D03*
X126358D03*
X124587D03*
X133445Y311136D03*
X131673D03*
X129902D03*
X128130D03*
X126358D03*
X124587D03*
X133445Y343136D03*
X131673D03*
X129902D03*
X128130D03*
X126358D03*
X124587D03*
X133445Y375136D03*
X131673D03*
X129902D03*
X128130D03*
X126358D03*
X124587D03*
X698679Y223397D03*
X700451D03*
X702222D03*
X703994D03*
X705766D03*
X707537D03*
X783053Y215136D03*
X781281D03*
X779510D03*
X777738D03*
X775966D03*
X774195D03*
X783053Y247136D03*
X781281D03*
X779510D03*
X777738D03*
X775966D03*
X774195D03*
X783053Y279136D03*
X781281D03*
X779510D03*
X777738D03*
X775966D03*
X774195D03*
X783053Y311136D03*
X781281D03*
X779510D03*
X777738D03*
X775966D03*
X774195D03*
X783053Y343136D03*
X781281D03*
X779510D03*
X777738D03*
X775966D03*
X774195D03*
X783003Y375136D03*
X781231D03*
X779460D03*
X777688D03*
X775916D03*
X774145D03*
X1363768Y2573D03*
X1365540D03*
X1367311D03*
X1369083D03*
X1370855D03*
X1372626D03*
X1364079Y34597D03*
X1365851D03*
X1367622D03*
X1369394D03*
X1371166D03*
X1372937D03*
X1366386Y393465D03*
X1368158D03*
X1369929D03*
X1371701D03*
X1373473D03*
X1375244D03*
X1368079Y581453D03*
X1369851D03*
X1371622D03*
X1373394D03*
X1375166D03*
X1376937D03*
X1368079Y612653D03*
X1369851D03*
X1371622D03*
X1373394D03*
X1375166D03*
X1376937D03*
G54D46*
X3000Y280500D03*
X5560D03*
X8120D03*
X10680D03*
X3000Y290500D03*
X8120D03*
X5560D03*
X10680D03*
G54D91*
X167124Y3233D03*
X163777D03*
X160431D03*
X157084D03*
X153738D03*
X150392D03*
X147045D03*
X143699D03*
X140352D03*
X137006D03*
X133659D03*
X130313D03*
X126966D03*
X123620D03*
X120273D03*
X116927D03*
X167124Y-14877D03*
X163777D03*
X160431D03*
X157084D03*
X153738D03*
X150392D03*
X147045D03*
X143699D03*
X140352D03*
X137006D03*
X133659D03*
X130313D03*
X126966D03*
X123620D03*
X120273D03*
X116927D03*
X167124Y22923D03*
X163777D03*
X160431D03*
X157084D03*
X153738D03*
X150392D03*
X147045D03*
X143699D03*
X140352D03*
X137006D03*
X133659D03*
X130313D03*
X126966D03*
X123620D03*
X120273D03*
X116927D03*
X167124Y78833D03*
X163777D03*
X160431D03*
X157084D03*
X153738D03*
X150392D03*
X147045D03*
X143699D03*
X140352D03*
X137006D03*
X133659D03*
X130313D03*
X126966D03*
X123620D03*
X120273D03*
X116927D03*
X167124Y60723D03*
X163777D03*
X160431D03*
X157084D03*
X153738D03*
X150392D03*
X147045D03*
X143699D03*
X140352D03*
X137006D03*
X133659D03*
X130313D03*
X126966D03*
X123620D03*
X120273D03*
X116927D03*
X167124Y41033D03*
X163777D03*
X160431D03*
X157084D03*
X153738D03*
X150392D03*
X147045D03*
X143699D03*
X140352D03*
X137006D03*
X133659D03*
X130313D03*
X126966D03*
X123620D03*
X120273D03*
X116927D03*
X167124Y523900D03*
X163777D03*
X160431D03*
X157084D03*
X153738D03*
X150392D03*
X147045D03*
X143699D03*
X140352D03*
X137006D03*
X133659D03*
X130313D03*
X126966D03*
X123620D03*
X120273D03*
X116927D03*
X167124Y542010D03*
X163777D03*
X160431D03*
X157084D03*
X153738D03*
X150392D03*
X147045D03*
X143699D03*
X140352D03*
X137006D03*
X133659D03*
X130313D03*
X126966D03*
X123620D03*
X120273D03*
X116927D03*
Y561700D03*
Y579810D03*
X120273Y561700D03*
X126966D03*
X133659D03*
X143699D03*
X150392D03*
X157084D03*
X163777D03*
X123620Y579810D03*
X130313D03*
X137006D03*
X147045D03*
X153738D03*
X160431D03*
X167124D03*
X137006Y561700D03*
X140352D03*
X143699Y579810D03*
X140352D03*
X120273D03*
X167124Y561700D03*
X150392Y579810D03*
X147045Y561700D03*
X126966Y579810D03*
X123620Y561700D03*
X157084Y579810D03*
X153738Y561700D03*
X133659Y579810D03*
X163777D03*
X160431Y561700D03*
X130313D03*
X167124Y617610D03*
X163777D03*
X160431D03*
X157084D03*
X153738D03*
X150392D03*
X147045D03*
X143699D03*
X140352D03*
X137006D03*
X133659D03*
X130313D03*
X126966D03*
X123620D03*
X120273D03*
X116927D03*
X167124Y599500D03*
X163777D03*
X160431D03*
X157084D03*
X153738D03*
X150392D03*
X147045D03*
X143699D03*
X140352D03*
X137006D03*
X133659D03*
X130313D03*
X126966D03*
X123620D03*
X120273D03*
X116927D03*
X230707Y3233D03*
X227360D03*
X224014D03*
X220667D03*
X217321D03*
X213974D03*
X210628D03*
X207281D03*
X203935D03*
X200588D03*
X197242D03*
X193896D03*
X190549D03*
X187203D03*
X183856D03*
X180510D03*
X177163D03*
X173817D03*
X170470D03*
X230707Y-14877D03*
X227360D03*
X224014D03*
X220667D03*
X217321D03*
X213974D03*
X210628D03*
X207281D03*
X203935D03*
X200588D03*
X197242D03*
X193896D03*
X190549D03*
X187203D03*
X183856D03*
X180510D03*
X177163D03*
X173817D03*
X170470D03*
X230707Y22923D03*
X227360D03*
X224014D03*
X220667D03*
X217321D03*
X213974D03*
X210628D03*
X207281D03*
X203935D03*
X200588D03*
X197242D03*
X193896D03*
X190549D03*
X187203D03*
X183856D03*
X180510D03*
X177163D03*
X173817D03*
X170470D03*
X230707Y78833D03*
X227360D03*
X224014D03*
X220667D03*
X217321D03*
X213974D03*
X210628D03*
X207281D03*
X203935D03*
X200588D03*
X197242D03*
X193896D03*
X190549D03*
X187203D03*
X183856D03*
X180510D03*
X177163D03*
X173817D03*
X170470D03*
X230707Y60723D03*
X227360D03*
X224014D03*
X220667D03*
X217321D03*
X213974D03*
X210628D03*
X207281D03*
X203935D03*
X200588D03*
X197242D03*
X193896D03*
X190549D03*
X187203D03*
X183856D03*
X180510D03*
X177163D03*
X173817D03*
X170470D03*
X230707Y41033D03*
X227360D03*
X224014D03*
X220667D03*
X217321D03*
X213974D03*
X210628D03*
X207281D03*
X203935D03*
X200588D03*
X197242D03*
X193896D03*
X190549D03*
X187203D03*
X183856D03*
X180510D03*
X177163D03*
X173817D03*
X170470D03*
X230707Y523900D03*
X227360D03*
X224014D03*
X220667D03*
X217321D03*
X213974D03*
X210628D03*
X207281D03*
X203935D03*
X200588D03*
X197242D03*
X193896D03*
X190549D03*
X187203D03*
X183856D03*
X180510D03*
X177163D03*
X173817D03*
X170470D03*
X230707Y542010D03*
X227360D03*
X224014D03*
X220667D03*
X217321D03*
X213974D03*
X210628D03*
X207281D03*
X203935D03*
X200588D03*
X197242D03*
X193896D03*
X190549D03*
X187203D03*
X183856D03*
X180510D03*
X177163D03*
X173817D03*
X170470D03*
Y561700D03*
X180510D03*
X187203D03*
X193896D03*
X200588D03*
X207281D03*
X217321D03*
X224014D03*
X230707D03*
X173817Y579810D03*
X183856D03*
X190549D03*
X197242D03*
X203935D03*
X210628D03*
X220667D03*
X227360D03*
X217321D03*
X213974D03*
X180510D03*
X177163D03*
X210628Y561700D03*
X213974D03*
X173817D03*
X177163D03*
X170470Y579810D03*
X224014D03*
X220667Y561700D03*
X200588Y579810D03*
X197242Y561700D03*
X230707Y579810D03*
X227360Y561700D03*
X207281Y579810D03*
X203935Y561700D03*
X187203Y579810D03*
X183856Y561700D03*
X193896Y579810D03*
X190549Y561700D03*
X230707Y617610D03*
X227360D03*
X224014D03*
X220667D03*
X217321D03*
X213974D03*
X210628D03*
X207281D03*
X203935D03*
X200588D03*
X197242D03*
X193896D03*
X190549D03*
X187203D03*
X183856D03*
X180510D03*
X177163D03*
X173817D03*
X170470D03*
X230707Y599500D03*
X227360D03*
X224014D03*
X220667D03*
X217321D03*
X213974D03*
X210628D03*
X207281D03*
X203935D03*
X200588D03*
X197242D03*
X193896D03*
X190549D03*
X187203D03*
X183856D03*
X180510D03*
X177163D03*
X173817D03*
X170470D03*
X290943Y3233D03*
X287596D03*
X284250D03*
X280903D03*
X277557D03*
X274210D03*
X270864D03*
X267518D03*
X264171D03*
X260825D03*
X257478D03*
X254132D03*
X250785D03*
X247439D03*
X244092D03*
X240746D03*
X237399D03*
X234053D03*
X290943Y-14877D03*
X287596D03*
X284250D03*
X280903D03*
X277557D03*
X274210D03*
X270864D03*
X267518D03*
X264171D03*
X260825D03*
X257478D03*
X254132D03*
X250785D03*
X247439D03*
X244092D03*
X240746D03*
X237399D03*
X234053D03*
X290943Y22923D03*
X287596D03*
X284250D03*
X280903D03*
X277557D03*
X274210D03*
X270864D03*
X267518D03*
X264171D03*
X260825D03*
X257478D03*
X254132D03*
X250785D03*
X247439D03*
X244092D03*
X240746D03*
X237399D03*
X234053D03*
X290943Y78833D03*
X287596D03*
X284250D03*
X280903D03*
X277557D03*
X274210D03*
X270864D03*
X267518D03*
X264171D03*
X260825D03*
X257478D03*
X254132D03*
X250785D03*
X247439D03*
X244092D03*
X240746D03*
X237399D03*
X234053D03*
X290943Y60723D03*
X287596D03*
X284250D03*
X280903D03*
X277557D03*
X274210D03*
X270864D03*
X267518D03*
X264171D03*
X260825D03*
X257478D03*
X254132D03*
X250785D03*
X247439D03*
X244092D03*
X240746D03*
X237399D03*
X234053D03*
X290943Y41033D03*
X287596D03*
X284250D03*
X280903D03*
X277557D03*
X274210D03*
X270864D03*
X267518D03*
X264171D03*
X260825D03*
X257478D03*
X254132D03*
X250785D03*
X247439D03*
X244092D03*
X240746D03*
X237399D03*
X234053D03*
X290943Y523900D03*
X287596D03*
X284250D03*
X280903D03*
X277557D03*
X274210D03*
X270864D03*
X267518D03*
X264171D03*
X260825D03*
X257478D03*
X254132D03*
X250785D03*
X247439D03*
X244092D03*
X240746D03*
X237399D03*
X234053D03*
X290943Y542010D03*
X287596D03*
X284250D03*
X280903D03*
X277557D03*
X274210D03*
X270864D03*
X267518D03*
X264171D03*
X260825D03*
X257478D03*
X254132D03*
X250785D03*
X247439D03*
X244092D03*
X240746D03*
X237399D03*
X234053D03*
X237399Y561700D03*
X244092D03*
X254132D03*
X260825D03*
X267518D03*
X274210D03*
X280903D03*
X290943D03*
X234053Y579810D03*
X240746D03*
X247439D03*
X257478D03*
X264171D03*
X270864D03*
X277557D03*
X284250D03*
X290943D03*
X287596D03*
X254132D03*
X250785D03*
X284250Y561700D03*
X287596D03*
X247439D03*
X250785D03*
X260825Y579810D03*
X257478Y561700D03*
X237399Y579810D03*
X234053Y561700D03*
X267518Y579810D03*
X264171Y561700D03*
X244092Y579810D03*
X240746Y561700D03*
X274210Y579810D03*
X270864Y561700D03*
X280903Y579810D03*
X277557Y561700D03*
X290943Y617610D03*
X287596D03*
X284250D03*
X280903D03*
X277557D03*
X274210D03*
X270864D03*
X267518D03*
X264171D03*
X260825D03*
X257478D03*
X254132D03*
X250785D03*
X247439D03*
X244092D03*
X240746D03*
X237399D03*
X234053D03*
X290943Y599500D03*
X287596D03*
X284250D03*
X280903D03*
X277557D03*
X274210D03*
X270864D03*
X267518D03*
X264171D03*
X260825D03*
X257478D03*
X254132D03*
X250785D03*
X247439D03*
X244092D03*
X240746D03*
X237399D03*
X234053D03*
X354525Y3233D03*
X351179D03*
X347833D03*
X344486D03*
X341140D03*
X337793D03*
X334447D03*
X331100D03*
X327754D03*
X324407D03*
X321061D03*
X317714D03*
X314368D03*
X311021D03*
X307675D03*
X304329D03*
X300982D03*
X297636D03*
X294289D03*
X354525Y-14877D03*
X351179D03*
X347833D03*
X344486D03*
X341140D03*
X337793D03*
X334447D03*
X331100D03*
X327754D03*
X324407D03*
X321061D03*
X317714D03*
X314368D03*
X311021D03*
X307675D03*
X304329D03*
X300982D03*
X297636D03*
X294289D03*
X354525Y22923D03*
X351179D03*
X347833D03*
X344486D03*
X341140D03*
X337793D03*
X334447D03*
X331100D03*
X327754D03*
X324407D03*
X321061D03*
X317714D03*
X314368D03*
X311021D03*
X307675D03*
X304329D03*
X300982D03*
X297636D03*
X294289D03*
X354525Y78833D03*
X351179D03*
X347833D03*
X344486D03*
X341140D03*
X337793D03*
X334447D03*
X331100D03*
X327754D03*
X324407D03*
X321061D03*
X317714D03*
X314368D03*
X311021D03*
X307675D03*
X304329D03*
X300982D03*
X297636D03*
X294289D03*
X354525Y60723D03*
X351179D03*
X347833D03*
X344486D03*
X341140D03*
X337793D03*
X334447D03*
X331100D03*
X327754D03*
X324407D03*
X321061D03*
X317714D03*
X314368D03*
X311021D03*
X307675D03*
X304329D03*
X300982D03*
X297636D03*
X294289D03*
X354525Y41033D03*
X351179D03*
X347833D03*
X344486D03*
X341140D03*
X337793D03*
X334447D03*
X331100D03*
X327754D03*
X324407D03*
X321061D03*
X317714D03*
X314368D03*
X311021D03*
X307675D03*
X304329D03*
X300982D03*
X297636D03*
X294289D03*
X354525Y523900D03*
X351179D03*
X347833D03*
X344486D03*
X341140D03*
X337793D03*
X334447D03*
X331100D03*
X327754D03*
X324407D03*
X321061D03*
X317714D03*
X314368D03*
X311021D03*
X307675D03*
X304329D03*
X300982D03*
X297636D03*
X294289D03*
X354525Y542010D03*
X351179D03*
X347833D03*
X344486D03*
X341140D03*
X337793D03*
X334447D03*
X331100D03*
X327754D03*
X324407D03*
X321061D03*
X317714D03*
X314368D03*
X311021D03*
X307675D03*
X304329D03*
X300982D03*
X297636D03*
X294289D03*
X341140Y579810D03*
X351179D03*
X311021Y561700D03*
X317714D03*
X327754D03*
X337793D03*
X347833D03*
X314368Y579810D03*
X321061D03*
X331100D03*
X297636Y561700D03*
X304329D03*
X294289Y579810D03*
X300982D03*
X307675D03*
X317714D03*
X307675Y561700D03*
X311021Y579810D03*
X314368Y561700D03*
X297636Y579810D03*
X294289Y561700D03*
X304329Y579810D03*
X300982Y561700D03*
X324407Y579810D03*
Y561700D03*
X327754Y579810D03*
X321061Y561700D03*
X334447D03*
X341140D03*
X337793Y579810D03*
X344486Y561700D03*
Y579810D03*
X347833D03*
X351179Y561700D03*
X354525Y579810D03*
X331100Y561700D03*
X334447Y579810D03*
X354525Y561700D03*
Y617610D03*
X351179D03*
X347833D03*
X344486D03*
X341140D03*
X337793D03*
X334447D03*
X331100D03*
X327754D03*
X324407D03*
X321061D03*
X317714D03*
X314368D03*
X311021D03*
X307675D03*
X304329D03*
X300982D03*
X297636D03*
X294289D03*
X354525Y599500D03*
X351179D03*
X347833D03*
X344486D03*
X341140D03*
X337793D03*
X334447D03*
X331100D03*
X327754D03*
X324407D03*
X321061D03*
X317714D03*
X314368D03*
X311021D03*
X307675D03*
X304329D03*
X300982D03*
X297636D03*
X294289D03*
X414762Y3233D03*
X411415D03*
X408069D03*
X404722D03*
X401376D03*
X398029D03*
X394683D03*
X371258D03*
X367911D03*
X364565D03*
X361218D03*
X357872D03*
X414762Y-14877D03*
X411415D03*
X408069D03*
X404722D03*
X401376D03*
X398029D03*
X394683D03*
X371258D03*
X367911D03*
X364565D03*
X361218D03*
X357872D03*
X414762Y22923D03*
X411415D03*
X408069D03*
X404722D03*
X401376D03*
X398029D03*
X394683D03*
X371258D03*
X367911D03*
X364565D03*
X361218D03*
X357872D03*
X414762Y78833D03*
X411415D03*
X408069D03*
X404722D03*
X401376D03*
X398029D03*
X394683D03*
X371258D03*
X367911D03*
X364565D03*
X361218D03*
X357872D03*
X414762Y60723D03*
X411415D03*
X408069D03*
X404722D03*
X401376D03*
X398029D03*
X394683D03*
X371258D03*
X367911D03*
X364565D03*
X361218D03*
X357872D03*
X414762Y41033D03*
X411415D03*
X408069D03*
X404722D03*
X401376D03*
X398029D03*
X394683D03*
X371258D03*
X367911D03*
X364565D03*
X361218D03*
X357872D03*
X414762Y523900D03*
X411415D03*
X408069D03*
X404722D03*
X401376D03*
X398029D03*
X394683D03*
X371258D03*
X367911D03*
X364565D03*
X361218D03*
X357872D03*
X414762Y542010D03*
X411415D03*
X408069D03*
X404722D03*
X401376D03*
X398029D03*
X394683D03*
X371258D03*
X367911D03*
X364565D03*
X361218D03*
X357872D03*
X371258Y561700D03*
Y579810D03*
X357872D03*
X367911D03*
X398029D03*
X408069D03*
X357872Y561700D03*
X367911D03*
X401376D03*
X411415D03*
X414762D03*
X411415Y579810D03*
X394683D03*
Y561700D03*
X361218Y579810D03*
X364565D03*
X361218Y561700D03*
X364565D03*
X401376Y579810D03*
X404722Y561700D03*
X408069D03*
X414762Y579810D03*
X404722D03*
X398029Y561700D03*
X414762Y617610D03*
X411415D03*
X408069D03*
X404722D03*
X401376D03*
X398029D03*
X394683D03*
X371258D03*
X367911D03*
X364565D03*
X361218D03*
X357872D03*
X414762Y599500D03*
X411415D03*
X408069D03*
X404722D03*
X401376D03*
X398029D03*
X394683D03*
X371258D03*
X367911D03*
X364565D03*
X361218D03*
X357872D03*
X478344Y3233D03*
X474998D03*
X471651D03*
X468305D03*
X464958D03*
X461612D03*
X458266D03*
X454919D03*
X451573D03*
X448226D03*
X444880D03*
X441533D03*
X438187D03*
X434840D03*
X431494D03*
X428147D03*
X424801D03*
X421455D03*
X418108D03*
X478344Y-14877D03*
X474998D03*
X471651D03*
X468305D03*
X464958D03*
X461612D03*
X458266D03*
X454919D03*
X451573D03*
X448226D03*
X444880D03*
X441533D03*
X438187D03*
X434840D03*
X431494D03*
X428147D03*
X424801D03*
X421455D03*
X418108D03*
X478344Y22923D03*
X474998D03*
X471651D03*
X468305D03*
X464958D03*
X461612D03*
X458266D03*
X454919D03*
X451573D03*
X448226D03*
X444880D03*
X441533D03*
X438187D03*
X434840D03*
X431494D03*
X428147D03*
X424801D03*
X421455D03*
X418108D03*
X478344Y78833D03*
X474998D03*
X471651D03*
X468305D03*
X464958D03*
X461612D03*
X458266D03*
X454919D03*
X451573D03*
X448226D03*
X444880D03*
X441533D03*
X438187D03*
X434840D03*
X431494D03*
X428147D03*
X424801D03*
X421455D03*
X418108D03*
X478344Y60723D03*
X474998D03*
X471651D03*
X468305D03*
X464958D03*
X461612D03*
X458266D03*
X454919D03*
X451573D03*
X448226D03*
X444880D03*
X441533D03*
X438187D03*
X434840D03*
X431494D03*
X428147D03*
X424801D03*
X421455D03*
X418108D03*
X478344Y41033D03*
X474998D03*
X471651D03*
X468305D03*
X464958D03*
X461612D03*
X458266D03*
X454919D03*
X451573D03*
X448226D03*
X444880D03*
X441533D03*
X438187D03*
X434840D03*
X431494D03*
X428147D03*
X424801D03*
X421455D03*
X418108D03*
X478344Y523900D03*
X474998D03*
X471651D03*
X468305D03*
X464958D03*
X461612D03*
X458266D03*
X454919D03*
X451573D03*
X448226D03*
X444880D03*
X441533D03*
X438187D03*
X434840D03*
X431494D03*
X428147D03*
X424801D03*
X421455D03*
X418108D03*
X478344Y542010D03*
X474998D03*
X471651D03*
X468305D03*
X464958D03*
X461612D03*
X458266D03*
X454919D03*
X451573D03*
X448226D03*
X444880D03*
X441533D03*
X438187D03*
X434840D03*
X431494D03*
X428147D03*
X424801D03*
X421455D03*
X418108D03*
Y579810D03*
X424801D03*
X431494D03*
X418108Y561700D03*
X428147D03*
X434840D03*
X441533D03*
Y579810D03*
X448226Y561700D03*
X454919D03*
X461612D03*
X471651D03*
X478344D03*
X451573Y579810D03*
X458266D03*
X464958D03*
X474998D03*
X471651D03*
X468305D03*
X464958Y561700D03*
X468305D03*
X421455Y579810D03*
X448226D03*
X444880D03*
Y561700D03*
X431494D03*
X438187D03*
X424801D03*
X478344Y579810D03*
X474998Y561700D03*
X454919Y579810D03*
X451573Y561700D03*
X461612Y579810D03*
X458266Y561700D03*
X438187Y579810D03*
X434840D03*
X421455Y561700D03*
X428147Y579810D03*
X478344Y617610D03*
X474998D03*
X471651D03*
X468305D03*
X464958D03*
X461612D03*
X458266D03*
X454919D03*
X451573D03*
X448226D03*
X444880D03*
X441533D03*
X438187D03*
X434840D03*
X431494D03*
X428147D03*
X424801D03*
X421455D03*
X418108D03*
X478344Y599500D03*
X474998D03*
X471651D03*
X468305D03*
X464958D03*
X461612D03*
X458266D03*
X454919D03*
X451573D03*
X448226D03*
X444880D03*
X441533D03*
X438187D03*
X434840D03*
X431494D03*
X428147D03*
X424801D03*
X421455D03*
X418108D03*
X538581Y3233D03*
X535234D03*
X531888D03*
X528541D03*
X525195D03*
X521848D03*
X518502D03*
X515155D03*
X511809D03*
X508462D03*
X505116D03*
X501770D03*
X498423D03*
X495077D03*
X491730D03*
X488384D03*
X485037D03*
X481691D03*
X538581Y-14877D03*
X535234D03*
X531888D03*
X528541D03*
X525195D03*
X521848D03*
X518502D03*
X515155D03*
X511809D03*
X508462D03*
X505116D03*
X501770D03*
X498423D03*
X495077D03*
X491730D03*
X488384D03*
X485037D03*
X481691D03*
X538581Y22923D03*
X535234D03*
X531888D03*
X528541D03*
X525195D03*
X521848D03*
X518502D03*
X515155D03*
X511809D03*
X508462D03*
X505116D03*
X501770D03*
X498423D03*
X495077D03*
X491730D03*
X488384D03*
X485037D03*
X481691D03*
X538581Y78833D03*
X535234D03*
X531888D03*
X528541D03*
X525195D03*
X521848D03*
X518502D03*
X515155D03*
X511809D03*
X508462D03*
X505116D03*
X501770D03*
X498423D03*
X495077D03*
X491730D03*
X488384D03*
X485037D03*
X481691D03*
X538581Y60723D03*
X535234D03*
X531888D03*
X528541D03*
X525195D03*
X521848D03*
X518502D03*
X515155D03*
X511809D03*
X508462D03*
X505116D03*
X501770D03*
X498423D03*
X495077D03*
X491730D03*
X488384D03*
X485037D03*
X481691D03*
X538581Y41033D03*
X535234D03*
X531888D03*
X528541D03*
X525195D03*
X521848D03*
X518502D03*
X515155D03*
X511809D03*
X508462D03*
X505116D03*
X501770D03*
X498423D03*
X495077D03*
X491730D03*
X488384D03*
X485037D03*
X481691D03*
X538581Y523900D03*
X535234D03*
X531888D03*
X528541D03*
X525195D03*
X521848D03*
X518502D03*
X515155D03*
X511809D03*
X508462D03*
X505116D03*
X501770D03*
X498423D03*
X495077D03*
X491730D03*
X488384D03*
X485037D03*
X481691D03*
X538581Y542010D03*
X535234D03*
X531888D03*
X528541D03*
X525195D03*
X521848D03*
X518502D03*
X515155D03*
X511809D03*
X508462D03*
X505116D03*
X501770D03*
X498423D03*
X495077D03*
X491730D03*
X488384D03*
X485037D03*
X481691D03*
X531888Y579810D03*
X538581D03*
X485037Y561700D03*
X491730D03*
X498423D03*
X508462D03*
X515155D03*
X521848D03*
X528541D03*
X535234D03*
X481691Y579810D03*
X488384D03*
X495077D03*
X501770D03*
X511809D03*
X518502D03*
X525195D03*
X508462D03*
X505116D03*
X538581Y561700D03*
X501770D03*
X505116D03*
X528541Y579810D03*
X525195Y561700D03*
X535234Y579810D03*
X531888Y561700D03*
X515155Y579810D03*
X511809Y561700D03*
X491730Y579810D03*
X488384Y561700D03*
X521848Y579810D03*
X518502Y561700D03*
X498423Y579810D03*
X495077Y561700D03*
X485037Y579810D03*
X481691Y561700D03*
X538581Y617610D03*
X535234D03*
X531888D03*
X528541D03*
X525195D03*
X521848D03*
X518502D03*
X515155D03*
X511809D03*
X508462D03*
X505116D03*
X501770D03*
X498423D03*
X495077D03*
X491730D03*
X488384D03*
X485037D03*
X481691D03*
X538581Y599500D03*
X535234D03*
X531888D03*
X528541D03*
X525195D03*
X521848D03*
X518502D03*
X515155D03*
X511809D03*
X508462D03*
X505116D03*
X501770D03*
X498423D03*
X495077D03*
X491730D03*
X488384D03*
X485037D03*
X481691D03*
X602163Y3233D03*
X598817D03*
X595470D03*
X592124D03*
X588777D03*
X585431D03*
X582084D03*
X578738D03*
X575392D03*
X572045D03*
X568699D03*
X565352D03*
X562006D03*
X558659D03*
X555313D03*
X551966D03*
X548620D03*
X545273D03*
X541927D03*
X602163Y-14877D03*
X598817D03*
X595470D03*
X592124D03*
X588777D03*
X585431D03*
X582084D03*
X578738D03*
X575392D03*
X572045D03*
X568699D03*
X565352D03*
X562006D03*
X558659D03*
X555313D03*
X551966D03*
X548620D03*
X545273D03*
X541927D03*
X602163Y22923D03*
X598817D03*
X595470D03*
X592124D03*
X588777D03*
X585431D03*
X582084D03*
X578738D03*
X575392D03*
X572045D03*
X568699D03*
X565352D03*
X562006D03*
X558659D03*
X555313D03*
X551966D03*
X548620D03*
X545273D03*
X541927D03*
X602163Y78833D03*
X598817D03*
X595470D03*
X592124D03*
X588777D03*
X585431D03*
X582084D03*
X578738D03*
X575392D03*
X572045D03*
X568699D03*
X565352D03*
X562006D03*
X558659D03*
X555313D03*
X551966D03*
X548620D03*
X545273D03*
X541927D03*
X602163Y60723D03*
X598817D03*
X595470D03*
X592124D03*
X588777D03*
X585431D03*
X582084D03*
X578738D03*
X575392D03*
X572045D03*
X568699D03*
X565352D03*
X562006D03*
X558659D03*
X555313D03*
X551966D03*
X548620D03*
X545273D03*
X541927D03*
X602163Y41033D03*
X598817D03*
X595470D03*
X592124D03*
X588777D03*
X585431D03*
X582084D03*
X578738D03*
X575392D03*
X572045D03*
X568699D03*
X565352D03*
X562006D03*
X558659D03*
X555313D03*
X551966D03*
X548620D03*
X545273D03*
X541927D03*
X602163Y523900D03*
X598817D03*
X595470D03*
X592124D03*
X588777D03*
X585431D03*
X582084D03*
X578738D03*
X575392D03*
X572045D03*
X568699D03*
X565352D03*
X562006D03*
X558659D03*
X555313D03*
X551966D03*
X548620D03*
X545273D03*
X541927D03*
X602163Y542010D03*
X598817D03*
X595470D03*
X592124D03*
X588777D03*
X585431D03*
X582084D03*
X578738D03*
X575392D03*
X572045D03*
X568699D03*
X565352D03*
X562006D03*
X558659D03*
X555313D03*
X551966D03*
X548620D03*
X545273D03*
X541927D03*
X548620Y579810D03*
X555313D03*
X562006D03*
X545273Y561700D03*
X551966D03*
X558659D03*
X565352D03*
X572045D03*
X568699Y579810D03*
X582084Y561700D03*
X588777D03*
X595470D03*
X575392Y579810D03*
X585431D03*
X592124D03*
X598817D03*
X582084D03*
X578738D03*
X545273D03*
X541927D03*
X575392Y561700D03*
X578738D03*
X541927D03*
X602163Y579810D03*
Y561700D03*
X598817D03*
X588777Y579810D03*
X585431Y561700D03*
X565352Y579810D03*
X562006Y561700D03*
X595470Y579810D03*
X592124Y561700D03*
X572045Y579810D03*
X568699Y561700D03*
X551966Y579810D03*
X548620Y561700D03*
X558659Y579810D03*
X555313Y561700D03*
X602163Y617610D03*
X598817D03*
X595470D03*
X592124D03*
X588777D03*
X585431D03*
X582084D03*
X578738D03*
X575392D03*
X572045D03*
X568699D03*
X565352D03*
X562006D03*
X558659D03*
X555313D03*
X551966D03*
X548620D03*
X545273D03*
X541927D03*
X602163Y599500D03*
X598817D03*
X595470D03*
X592124D03*
X588777D03*
X585431D03*
X582084D03*
X578738D03*
X575392D03*
X572045D03*
X568699D03*
X565352D03*
X562006D03*
X558659D03*
X555313D03*
X551966D03*
X548620D03*
X545273D03*
X541927D03*
X615549Y3233D03*
X612203D03*
X608856D03*
X605510D03*
X615549Y-14877D03*
X612203D03*
X608856D03*
X605510D03*
X615549Y22923D03*
X612203D03*
X608856D03*
X605510D03*
X615549Y78833D03*
X612203D03*
X608856D03*
X605510D03*
X615549Y60723D03*
X612203D03*
X608856D03*
X605510D03*
X615549Y41033D03*
X612203D03*
X608856D03*
X605510D03*
X615549Y523900D03*
X612203D03*
X608856D03*
X605510D03*
X615549Y542010D03*
X612203D03*
X608856D03*
X605510D03*
X608856Y561700D03*
X612203D03*
X615549Y579810D03*
X608856D03*
X612203D03*
X605510D03*
Y561700D03*
X615549D03*
Y617610D03*
X612203D03*
X608856D03*
X605510D03*
X615549Y599500D03*
X612203D03*
X608856D03*
X605510D03*
X786616Y3233D03*
X783269D03*
X779923D03*
X776576D03*
X773230D03*
X769883D03*
X766537D03*
X786616Y-14877D03*
X783269D03*
X779923D03*
X776576D03*
X773230D03*
X769883D03*
X766537D03*
X786616Y22923D03*
X783269D03*
X779923D03*
X776576D03*
X773230D03*
X769883D03*
X766537D03*
X786616Y78833D03*
X783269D03*
X779923D03*
X776576D03*
X773230D03*
X769883D03*
X766537D03*
X786616Y60723D03*
X783269D03*
X779923D03*
X776576D03*
X773230D03*
X769883D03*
X766537D03*
X786616Y41033D03*
X783269D03*
X779923D03*
X776576D03*
X773230D03*
X769883D03*
X766537D03*
X786616Y523900D03*
X783269D03*
X779923D03*
X776576D03*
X773230D03*
X769883D03*
X766537D03*
X786616Y579810D03*
X783269D03*
X779923D03*
X776576D03*
X773230D03*
X769883D03*
X766537D03*
X786616Y561700D03*
X783269D03*
X779923D03*
X776576D03*
X773230D03*
X769883D03*
X766537D03*
X786616Y542010D03*
X783269D03*
X779923D03*
X776576D03*
X773230D03*
X769883D03*
X766537D03*
X786616Y617610D03*
X783269D03*
X779923D03*
X776576D03*
X773230D03*
X769883D03*
X766537D03*
X786616Y599500D03*
X783269D03*
X779923D03*
X776576D03*
X773230D03*
X769883D03*
X766537D03*
X846852Y3233D03*
X843506D03*
X840159D03*
X836813D03*
X833466D03*
X830120D03*
X826773D03*
X823427D03*
X820080D03*
X816734D03*
X813387D03*
X810041D03*
X806694D03*
X803348D03*
X800002D03*
X796655D03*
X793309D03*
X789962D03*
X846852Y-14877D03*
X843506D03*
X840159D03*
X836813D03*
X833466D03*
X830120D03*
X826773D03*
X823427D03*
X820080D03*
X816734D03*
X813387D03*
X810041D03*
X806694D03*
X803348D03*
X800002D03*
X796655D03*
X793309D03*
X789962D03*
X846852Y22923D03*
X843506D03*
X840159D03*
X836813D03*
X833466D03*
X830120D03*
X826773D03*
X823427D03*
X820080D03*
X816734D03*
X813387D03*
X810041D03*
X806694D03*
X803348D03*
X800002D03*
X796655D03*
X793309D03*
X789962D03*
X846852Y78833D03*
X843506D03*
X840159D03*
X836813D03*
X833466D03*
X830120D03*
X826773D03*
X823427D03*
X820080D03*
X816734D03*
X813387D03*
X810041D03*
X806694D03*
X803348D03*
X800002D03*
X796655D03*
X793309D03*
X789962D03*
X846852Y60723D03*
X843506D03*
X840159D03*
X836813D03*
X833466D03*
X830120D03*
X826773D03*
X823427D03*
X820080D03*
X816734D03*
X813387D03*
X810041D03*
X806694D03*
X803348D03*
X800002D03*
X796655D03*
X793309D03*
X789962D03*
X846852Y41033D03*
X843506D03*
X840159D03*
X836813D03*
X833466D03*
X830120D03*
X826773D03*
X823427D03*
X820080D03*
X816734D03*
X813387D03*
X810041D03*
X806694D03*
X803348D03*
X800002D03*
X796655D03*
X793309D03*
X789962D03*
X846852Y523900D03*
X843506D03*
X840159D03*
X836813D03*
X833466D03*
X830120D03*
X826773D03*
X823427D03*
X820080D03*
X816734D03*
X813387D03*
X810041D03*
X806694D03*
X803348D03*
X800002D03*
X796655D03*
X793309D03*
X789962D03*
X846852Y579810D03*
X843506D03*
X840159D03*
X836813D03*
X833466D03*
X830120D03*
X826773D03*
X823427D03*
X820080D03*
X816734D03*
X813387D03*
X810041D03*
X806694D03*
X803348D03*
X800002D03*
X796655D03*
X793309D03*
X789962D03*
X846852Y561700D03*
X843506D03*
X840159D03*
X836813D03*
X833466D03*
X830120D03*
X826773D03*
X823427D03*
X820080D03*
X816734D03*
X813387D03*
X810041D03*
X806694D03*
X803348D03*
X800002D03*
X796655D03*
X793309D03*
X789962D03*
X846852Y542010D03*
X843506D03*
X840159D03*
X836813D03*
X833466D03*
X830120D03*
X826773D03*
X823427D03*
X820080D03*
X816734D03*
X813387D03*
X810041D03*
X806694D03*
X803348D03*
X800002D03*
X796655D03*
X793309D03*
X789962D03*
X846852Y617610D03*
X843506D03*
X840159D03*
X836813D03*
X833466D03*
X830120D03*
X826773D03*
X823427D03*
X820080D03*
X816734D03*
X813387D03*
X810041D03*
X806694D03*
X803348D03*
X800002D03*
X796655D03*
X793309D03*
X789962D03*
X846852Y599500D03*
X843506D03*
X840159D03*
X836813D03*
X833466D03*
X830120D03*
X826773D03*
X823427D03*
X820080D03*
X816734D03*
X813387D03*
X810041D03*
X806694D03*
X803348D03*
X800002D03*
X796655D03*
X793309D03*
X789962D03*
X910435Y3233D03*
X907088D03*
X903742D03*
X900395D03*
X897049D03*
X893702D03*
X890356D03*
X887009D03*
X883663D03*
X880317D03*
X876970D03*
X873624D03*
X870277D03*
X866931D03*
X863584D03*
X860238D03*
X856891D03*
X853545D03*
X850198D03*
X910435Y-14877D03*
X907088D03*
X903742D03*
X900395D03*
X897049D03*
X893702D03*
X890356D03*
X887009D03*
X883663D03*
X880317D03*
X876970D03*
X873624D03*
X870277D03*
X866931D03*
X863584D03*
X860238D03*
X856891D03*
X853545D03*
X850198D03*
X910435Y22923D03*
X907088D03*
X903742D03*
X900395D03*
X897049D03*
X893702D03*
X890356D03*
X887009D03*
X883663D03*
X880317D03*
X876970D03*
X873624D03*
X870277D03*
X866931D03*
X863584D03*
X860238D03*
X856891D03*
X853545D03*
X850198D03*
X910435Y78833D03*
X907088D03*
X903742D03*
X900395D03*
X897049D03*
X893702D03*
X890356D03*
X887009D03*
X883663D03*
X880317D03*
X876970D03*
X873624D03*
X870277D03*
X866931D03*
X863584D03*
X860238D03*
X856891D03*
X853545D03*
X850198D03*
X910435Y60723D03*
X907088D03*
X903742D03*
X900395D03*
X897049D03*
X893702D03*
X890356D03*
X887009D03*
X883663D03*
X880317D03*
X876970D03*
X873624D03*
X870277D03*
X866931D03*
X863584D03*
X860238D03*
X856891D03*
X853545D03*
X850198D03*
X910435Y41033D03*
X907088D03*
X903742D03*
X900395D03*
X897049D03*
X893702D03*
X890356D03*
X887009D03*
X883663D03*
X880317D03*
X876970D03*
X873624D03*
X870277D03*
X866931D03*
X863584D03*
X860238D03*
X856891D03*
X853545D03*
X850198D03*
X910435Y523900D03*
X907088D03*
X903742D03*
X900395D03*
X897049D03*
X893702D03*
X890356D03*
X887009D03*
X883663D03*
X880317D03*
X876970D03*
X873624D03*
X870277D03*
X866931D03*
X863584D03*
X860238D03*
X856891D03*
X853545D03*
X850198D03*
X910435Y579810D03*
X907088D03*
X903742D03*
X900395D03*
X897049D03*
X893702D03*
X890356D03*
X887009D03*
X883663D03*
X880317D03*
X876970D03*
X873624D03*
X870277D03*
X866931D03*
X863584D03*
X860238D03*
X856891D03*
X853545D03*
X850198D03*
X910435Y561700D03*
X907088D03*
X903742D03*
X900395D03*
X897049D03*
X893702D03*
X890356D03*
X887009D03*
X883663D03*
X880317D03*
X876970D03*
X873624D03*
X870277D03*
X866931D03*
X863584D03*
X860238D03*
X856891D03*
X853545D03*
X850198D03*
X910435Y542010D03*
X907088D03*
X903742D03*
X900395D03*
X897049D03*
X893702D03*
X890356D03*
X887009D03*
X883663D03*
X880317D03*
X876970D03*
X873624D03*
X870277D03*
X866931D03*
X863584D03*
X860238D03*
X856891D03*
X853545D03*
X850198D03*
X910435Y617610D03*
X907088D03*
X903742D03*
X900395D03*
X897049D03*
X893702D03*
X890356D03*
X887009D03*
X883663D03*
X880317D03*
X876970D03*
X873624D03*
X870277D03*
X866931D03*
X863584D03*
X860238D03*
X856891D03*
X853545D03*
X850198D03*
X910435Y599500D03*
X907088D03*
X903742D03*
X900395D03*
X897049D03*
X893702D03*
X890356D03*
X887009D03*
X883663D03*
X880317D03*
X876970D03*
X873624D03*
X870277D03*
X866931D03*
X863584D03*
X860238D03*
X856891D03*
X853545D03*
X850198D03*
X970671Y3233D03*
X967324D03*
X963978D03*
X960631D03*
X957285D03*
X953939D03*
X950592D03*
X947246D03*
X943899D03*
X940553D03*
X937206D03*
X933860D03*
X930513D03*
X927167D03*
X923820D03*
X920474D03*
X917128D03*
X913781D03*
X970671Y-14877D03*
X967324D03*
X963978D03*
X960631D03*
X957285D03*
X953939D03*
X950592D03*
X947246D03*
X943899D03*
X940553D03*
X937206D03*
X933860D03*
X930513D03*
X927167D03*
X923820D03*
X920474D03*
X917128D03*
X913781D03*
X970671Y22923D03*
X967324D03*
X963978D03*
X960631D03*
X957285D03*
X953939D03*
X950592D03*
X947246D03*
X943899D03*
X940553D03*
X937206D03*
X933860D03*
X930513D03*
X927167D03*
X923820D03*
X920474D03*
X917128D03*
X913781D03*
X970671Y78833D03*
X967324D03*
X963978D03*
X960631D03*
X957285D03*
X953939D03*
X950592D03*
X947246D03*
X943899D03*
X940553D03*
X937206D03*
X933860D03*
X930513D03*
X927167D03*
X923820D03*
X920474D03*
X917128D03*
X913781D03*
X970671Y60723D03*
X967324D03*
X963978D03*
X960631D03*
X957285D03*
X953939D03*
X950592D03*
X947246D03*
X943899D03*
X940553D03*
X937206D03*
X933860D03*
X930513D03*
X927167D03*
X923820D03*
X920474D03*
X917128D03*
X913781D03*
X970671Y41033D03*
X967324D03*
X963978D03*
X960631D03*
X957285D03*
X953939D03*
X950592D03*
X947246D03*
X943899D03*
X940553D03*
X937206D03*
X933860D03*
X930513D03*
X927167D03*
X923820D03*
X920474D03*
X917128D03*
X913781D03*
X970671Y523900D03*
X967324D03*
X963978D03*
X960631D03*
X957285D03*
X953939D03*
X950592D03*
X947246D03*
X943899D03*
X940553D03*
X937206D03*
X933860D03*
X930513D03*
X927167D03*
X923820D03*
X920474D03*
X917128D03*
X913781D03*
X970671Y579810D03*
X967324D03*
X963978D03*
X960631D03*
X957285D03*
X953939D03*
X950592D03*
X947246D03*
X943899D03*
X940553D03*
X937206D03*
X933860D03*
X930513D03*
X927167D03*
X923820D03*
X920474D03*
X917128D03*
X913781D03*
X970671Y561700D03*
X967324D03*
X963978D03*
X960631D03*
X957285D03*
X953939D03*
X950592D03*
X947246D03*
X943899D03*
X940553D03*
X937206D03*
X933860D03*
X930513D03*
X927167D03*
X923820D03*
X920474D03*
X917128D03*
X913781D03*
X970671Y542010D03*
X967324D03*
X963978D03*
X960631D03*
X957285D03*
X953939D03*
X950592D03*
X947246D03*
X943899D03*
X940553D03*
X937206D03*
X933860D03*
X930513D03*
X927167D03*
X923820D03*
X920474D03*
X917128D03*
X913781D03*
X970671Y617610D03*
X967324D03*
X963978D03*
X960631D03*
X957285D03*
X953939D03*
X950592D03*
X947246D03*
X943899D03*
X940553D03*
X937206D03*
X933860D03*
X930513D03*
X927167D03*
X923820D03*
X920474D03*
X917128D03*
X913781D03*
X970671Y599500D03*
X967324D03*
X963978D03*
X960631D03*
X957285D03*
X953939D03*
X950592D03*
X947246D03*
X943899D03*
X940553D03*
X937206D03*
X933860D03*
X930513D03*
X927167D03*
X923820D03*
X920474D03*
X917128D03*
X913781D03*
X1020868Y3233D03*
X1017521D03*
X1014175D03*
X1010828D03*
X1007482D03*
X1004135D03*
X1000789D03*
X997443D03*
X994096D03*
X990750D03*
X987403D03*
X984057D03*
X980710D03*
X977364D03*
X974017D03*
X1020868Y-14877D03*
X1017521D03*
X1014175D03*
X1010828D03*
X1007482D03*
X1004135D03*
X1000789D03*
X997443D03*
X994096D03*
X990750D03*
X987403D03*
X984057D03*
X980710D03*
X977364D03*
X974017D03*
X1020868Y22923D03*
X1017521D03*
X1014175D03*
X1010828D03*
X1007482D03*
X1004135D03*
X1000789D03*
X997443D03*
X994096D03*
X990750D03*
X987403D03*
X984057D03*
X980710D03*
X977364D03*
X974017D03*
X1020868Y78833D03*
X1017521D03*
X1014175D03*
X1010828D03*
X1007482D03*
X1004135D03*
X1000789D03*
X997443D03*
X994096D03*
X990750D03*
X987403D03*
X984057D03*
X980710D03*
X977364D03*
X974017D03*
X1020868Y60723D03*
X1017521D03*
X1014175D03*
X1010828D03*
X1007482D03*
X1004135D03*
X1000789D03*
X997443D03*
X994096D03*
X990750D03*
X987403D03*
X984057D03*
X980710D03*
X977364D03*
X974017D03*
X1020868Y41033D03*
X1017521D03*
X1014175D03*
X1010828D03*
X1007482D03*
X1004135D03*
X1000789D03*
X997443D03*
X994096D03*
X990750D03*
X987403D03*
X984057D03*
X980710D03*
X977364D03*
X974017D03*
X1020868Y523900D03*
X1017521D03*
X1014175D03*
X1010828D03*
X1007482D03*
X1004135D03*
X1000789D03*
X997443D03*
X994096D03*
X990750D03*
X987403D03*
X984057D03*
X980710D03*
X977364D03*
X974017D03*
X1020868Y579810D03*
X1017521D03*
X1014175D03*
X1010828D03*
X1007482D03*
X1004135D03*
X1000789D03*
X997443D03*
X994096D03*
X990750D03*
X987403D03*
X984057D03*
X980710D03*
X977364D03*
X974017D03*
X1020868Y561700D03*
X1017521D03*
X1014175D03*
X1010828D03*
X1007482D03*
X1004135D03*
X1000789D03*
X997443D03*
X994096D03*
X990750D03*
X987403D03*
X984057D03*
X980710D03*
X977364D03*
X974017D03*
X1020868Y542010D03*
X1017521D03*
X1014175D03*
X1010828D03*
X1007482D03*
X1004135D03*
X1000789D03*
X997443D03*
X994096D03*
X990750D03*
X987403D03*
X984057D03*
X980710D03*
X977364D03*
X974017D03*
X1020868Y617610D03*
X1017521D03*
X1014175D03*
X1010828D03*
X1007482D03*
X1004135D03*
X1000789D03*
X997443D03*
X994096D03*
X990750D03*
X987403D03*
X984057D03*
X980710D03*
X977364D03*
X974017D03*
X1020868Y599500D03*
X1017521D03*
X1014175D03*
X1010828D03*
X1007482D03*
X1004135D03*
X1000789D03*
X997443D03*
X994096D03*
X990750D03*
X987403D03*
X984057D03*
X980710D03*
X977364D03*
X974017D03*
X1094490Y3233D03*
X1091143D03*
X1087797D03*
X1084450D03*
X1081104D03*
X1077757D03*
X1074411D03*
X1071065D03*
X1067718D03*
X1064372D03*
X1061025D03*
X1057679D03*
X1054332D03*
X1050986D03*
X1047639D03*
X1044293D03*
X1094490Y-14877D03*
X1091143D03*
X1087797D03*
X1084450D03*
X1081104D03*
X1077757D03*
X1074411D03*
X1071065D03*
X1067718D03*
X1064372D03*
X1061025D03*
X1057679D03*
X1054332D03*
X1050986D03*
X1047639D03*
X1044293D03*
X1094490Y22923D03*
X1091143D03*
X1087797D03*
X1084450D03*
X1081104D03*
X1077757D03*
X1074411D03*
X1071065D03*
X1067718D03*
X1064372D03*
X1061025D03*
X1057679D03*
X1054332D03*
X1050986D03*
X1047639D03*
X1044293D03*
X1094490Y78833D03*
X1091143D03*
X1087797D03*
X1084450D03*
X1081104D03*
X1077757D03*
X1074411D03*
X1071065D03*
X1067718D03*
X1064372D03*
X1061025D03*
X1057679D03*
X1054332D03*
X1050986D03*
X1047639D03*
X1044293D03*
X1094490Y60723D03*
X1091143D03*
X1087797D03*
X1084450D03*
X1081104D03*
X1077757D03*
X1074411D03*
X1071065D03*
X1067718D03*
X1064372D03*
X1061025D03*
X1057679D03*
X1054332D03*
X1050986D03*
X1047639D03*
X1044293D03*
X1094490Y41033D03*
X1091143D03*
X1087797D03*
X1084450D03*
X1081104D03*
X1077757D03*
X1074411D03*
X1071065D03*
X1067718D03*
X1064372D03*
X1061025D03*
X1057679D03*
X1054332D03*
X1050986D03*
X1047639D03*
X1044293D03*
X1094490Y523900D03*
X1091143D03*
X1087797D03*
X1084450D03*
X1081104D03*
X1077757D03*
X1074411D03*
X1071065D03*
X1067718D03*
X1064372D03*
X1061025D03*
X1057679D03*
X1054332D03*
X1050986D03*
X1047639D03*
X1044293D03*
X1094490Y579810D03*
X1091143D03*
X1087797D03*
X1084450D03*
X1081104D03*
X1077757D03*
X1074411D03*
X1071065D03*
X1067718D03*
X1064372D03*
X1061025D03*
X1057679D03*
X1054332D03*
X1050986D03*
X1047639D03*
X1044293D03*
X1094490Y561700D03*
X1091143D03*
X1087797D03*
X1084450D03*
X1081104D03*
X1077757D03*
X1074411D03*
X1071065D03*
X1067718D03*
X1064372D03*
X1061025D03*
X1057679D03*
X1054332D03*
X1050986D03*
X1047639D03*
X1044293D03*
X1094490Y542010D03*
X1091143D03*
X1087797D03*
X1084450D03*
X1081104D03*
X1077757D03*
X1074411D03*
X1071065D03*
X1067718D03*
X1064372D03*
X1061025D03*
X1057679D03*
X1054332D03*
X1050986D03*
X1047639D03*
X1044293D03*
X1094490Y617610D03*
X1091143D03*
X1087797D03*
X1084450D03*
X1081104D03*
X1077757D03*
X1074411D03*
X1071065D03*
X1067718D03*
X1064372D03*
X1061025D03*
X1057679D03*
X1054332D03*
X1050986D03*
X1047639D03*
X1044293D03*
X1094490Y599500D03*
X1091143D03*
X1087797D03*
X1084450D03*
X1081104D03*
X1077757D03*
X1074411D03*
X1071065D03*
X1067718D03*
X1064372D03*
X1061025D03*
X1057679D03*
X1054332D03*
X1050986D03*
X1047639D03*
X1044293D03*
X1154726Y3233D03*
X1151380D03*
X1148033D03*
X1144687D03*
X1141340D03*
X1137994D03*
X1134647D03*
X1131301D03*
X1127954D03*
X1124608D03*
X1121261D03*
X1117915D03*
X1114568D03*
X1111222D03*
X1107876D03*
X1104529D03*
X1101183D03*
X1097836D03*
X1154726Y-14877D03*
X1151380D03*
X1148033D03*
X1144687D03*
X1141340D03*
X1137994D03*
X1134647D03*
X1131301D03*
X1127954D03*
X1124608D03*
X1121261D03*
X1117915D03*
X1114568D03*
X1111222D03*
X1107876D03*
X1104529D03*
X1101183D03*
X1097836D03*
X1154726Y22923D03*
X1151380D03*
X1148033D03*
X1144687D03*
X1141340D03*
X1137994D03*
X1134647D03*
X1131301D03*
X1127954D03*
X1124608D03*
X1121261D03*
X1117915D03*
X1114568D03*
X1111222D03*
X1107876D03*
X1104529D03*
X1101183D03*
X1097836D03*
X1154726Y78833D03*
X1151380D03*
X1148033D03*
X1144687D03*
X1141340D03*
X1137994D03*
X1134647D03*
X1131301D03*
X1127954D03*
X1124608D03*
X1121261D03*
X1117915D03*
X1114568D03*
X1111222D03*
X1107876D03*
X1104529D03*
X1101183D03*
X1097836D03*
X1154726Y60723D03*
X1151380D03*
X1148033D03*
X1144687D03*
X1141340D03*
X1137994D03*
X1134647D03*
X1131301D03*
X1127954D03*
X1124608D03*
X1121261D03*
X1117915D03*
X1114568D03*
X1111222D03*
X1107876D03*
X1104529D03*
X1101183D03*
X1097836D03*
X1154726Y41033D03*
X1151380D03*
X1148033D03*
X1144687D03*
X1141340D03*
X1137994D03*
X1134647D03*
X1131301D03*
X1127954D03*
X1124608D03*
X1121261D03*
X1117915D03*
X1114568D03*
X1111222D03*
X1107876D03*
X1104529D03*
X1101183D03*
X1097836D03*
X1154726Y523900D03*
X1151380D03*
X1148033D03*
X1144687D03*
X1141340D03*
X1137994D03*
X1134647D03*
X1131301D03*
X1127954D03*
X1124608D03*
X1121261D03*
X1117915D03*
X1114568D03*
X1111222D03*
X1107876D03*
X1104529D03*
X1101183D03*
X1097836D03*
X1154726Y579810D03*
X1151380D03*
X1148033D03*
X1144687D03*
X1141340D03*
X1137994D03*
X1134647D03*
X1131301D03*
X1127954D03*
X1124608D03*
X1121261D03*
X1117915D03*
X1114568D03*
X1111222D03*
X1107876D03*
X1104529D03*
X1101183D03*
X1097836D03*
X1154726Y561700D03*
X1151380D03*
X1148033D03*
X1144687D03*
X1141340D03*
X1137994D03*
X1134647D03*
X1131301D03*
X1127954D03*
X1124608D03*
X1121261D03*
X1117915D03*
X1114568D03*
X1111222D03*
X1107876D03*
X1104529D03*
X1101183D03*
X1097836D03*
X1154726Y542010D03*
X1151380D03*
X1148033D03*
X1144687D03*
X1141340D03*
X1137994D03*
X1134647D03*
X1131301D03*
X1127954D03*
X1124608D03*
X1121261D03*
X1117915D03*
X1114568D03*
X1111222D03*
X1107876D03*
X1104529D03*
X1101183D03*
X1097836D03*
X1154726Y617610D03*
X1151380D03*
X1148033D03*
X1144687D03*
X1141340D03*
X1137994D03*
X1134647D03*
X1131301D03*
X1127954D03*
X1124608D03*
X1121261D03*
X1117915D03*
X1114568D03*
X1111222D03*
X1107876D03*
X1104529D03*
X1101183D03*
X1097836D03*
X1154726Y599500D03*
X1151380D03*
X1148033D03*
X1144687D03*
X1141340D03*
X1137994D03*
X1134647D03*
X1131301D03*
X1127954D03*
X1124608D03*
X1121261D03*
X1117915D03*
X1114568D03*
X1111222D03*
X1107876D03*
X1104529D03*
X1101183D03*
X1097836D03*
X1218309Y3233D03*
X1214962D03*
X1211616D03*
X1208269D03*
X1204923D03*
X1201576D03*
X1198230D03*
X1194883D03*
X1191537D03*
X1188191D03*
X1184844D03*
X1181498D03*
X1178151D03*
X1174805D03*
X1171458D03*
X1168112D03*
X1164765D03*
X1161419D03*
X1158072D03*
X1218309Y-14877D03*
X1214962D03*
X1211616D03*
X1208269D03*
X1204923D03*
X1201576D03*
X1198230D03*
X1194883D03*
X1191537D03*
X1188191D03*
X1184844D03*
X1181498D03*
X1178151D03*
X1174805D03*
X1171458D03*
X1168112D03*
X1164765D03*
X1161419D03*
X1158072D03*
X1218309Y22923D03*
X1214962D03*
X1211616D03*
X1208269D03*
X1204923D03*
X1201576D03*
X1198230D03*
X1194883D03*
X1191537D03*
X1188191D03*
X1184844D03*
X1181498D03*
X1178151D03*
X1174805D03*
X1171458D03*
X1168112D03*
X1164765D03*
X1161419D03*
X1158072D03*
X1218309Y78833D03*
X1214962D03*
X1211616D03*
X1208269D03*
X1204923D03*
X1201576D03*
X1198230D03*
X1194883D03*
X1191537D03*
X1188191D03*
X1184844D03*
X1181498D03*
X1178151D03*
X1174805D03*
X1171458D03*
X1168112D03*
X1164765D03*
X1161419D03*
X1158072D03*
X1218309Y60723D03*
X1214962D03*
X1211616D03*
X1208269D03*
X1204923D03*
X1201576D03*
X1198230D03*
X1194883D03*
X1191537D03*
X1188191D03*
X1184844D03*
X1181498D03*
X1178151D03*
X1174805D03*
X1171458D03*
X1168112D03*
X1164765D03*
X1161419D03*
X1158072D03*
X1218309Y41033D03*
X1214962D03*
X1211616D03*
X1208269D03*
X1204923D03*
X1201576D03*
X1198230D03*
X1194883D03*
X1191537D03*
X1188191D03*
X1184844D03*
X1181498D03*
X1178151D03*
X1174805D03*
X1171458D03*
X1168112D03*
X1164765D03*
X1161419D03*
X1158072D03*
X1218309Y523900D03*
X1214962D03*
X1211616D03*
X1208269D03*
X1204923D03*
X1201576D03*
X1198230D03*
X1194883D03*
X1191537D03*
X1188191D03*
X1184844D03*
X1181498D03*
X1178151D03*
X1174805D03*
X1171458D03*
X1168112D03*
X1164765D03*
X1161419D03*
X1158072D03*
X1218309Y579810D03*
X1214962D03*
X1211616D03*
X1208269D03*
X1204923D03*
X1201576D03*
X1198230D03*
X1194883D03*
X1191537D03*
X1188191D03*
X1184844D03*
X1181498D03*
X1178151D03*
X1174805D03*
X1171458D03*
X1168112D03*
X1164765D03*
X1161419D03*
X1158072D03*
X1218309Y561700D03*
X1214962D03*
X1211616D03*
X1208269D03*
X1204923D03*
X1201576D03*
X1198230D03*
X1194883D03*
X1191537D03*
X1188191D03*
X1184844D03*
X1181498D03*
X1178151D03*
X1174805D03*
X1171458D03*
X1168112D03*
X1164765D03*
X1161419D03*
X1158072D03*
X1218309Y542010D03*
X1214962D03*
X1211616D03*
X1208269D03*
X1204923D03*
X1201576D03*
X1198230D03*
X1194883D03*
X1191537D03*
X1188191D03*
X1184844D03*
X1181498D03*
X1178151D03*
X1174805D03*
X1171458D03*
X1168112D03*
X1164765D03*
X1161419D03*
X1158072D03*
X1218309Y617610D03*
X1214962D03*
X1211616D03*
X1208269D03*
X1204923D03*
X1201576D03*
X1198230D03*
X1194883D03*
X1191537D03*
X1188191D03*
X1184844D03*
X1181498D03*
X1178151D03*
X1174805D03*
X1171458D03*
X1168112D03*
X1164765D03*
X1161419D03*
X1158072D03*
X1218309Y599500D03*
X1214962D03*
X1211616D03*
X1208269D03*
X1204923D03*
X1201576D03*
X1198230D03*
X1194883D03*
X1191537D03*
X1188191D03*
X1184844D03*
X1181498D03*
X1178151D03*
X1174805D03*
X1171458D03*
X1168112D03*
X1164765D03*
X1161419D03*
X1158072D03*
X1265159Y3233D03*
X1261813D03*
X1258466D03*
X1255120D03*
X1251773D03*
X1248427D03*
X1245080D03*
X1241734D03*
X1238387D03*
X1235041D03*
X1231694D03*
X1228348D03*
X1225002D03*
X1221655D03*
X1265159Y-14877D03*
X1261813D03*
X1258466D03*
X1255120D03*
X1251773D03*
X1248427D03*
X1245080D03*
X1241734D03*
X1238387D03*
X1235041D03*
X1231694D03*
X1228348D03*
X1225002D03*
X1221655D03*
X1265159Y22923D03*
X1261813D03*
X1258466D03*
X1255120D03*
X1251773D03*
X1248427D03*
X1245080D03*
X1241734D03*
X1238387D03*
X1235041D03*
X1231694D03*
X1228348D03*
X1225002D03*
X1221655D03*
X1265159Y78833D03*
X1261813D03*
X1258466D03*
X1255120D03*
X1251773D03*
X1248427D03*
X1245080D03*
X1241734D03*
X1238387D03*
X1235041D03*
X1231694D03*
X1228348D03*
X1225002D03*
X1221655D03*
X1265159Y60723D03*
X1261813D03*
X1258466D03*
X1255120D03*
X1251773D03*
X1248427D03*
X1245080D03*
X1241734D03*
X1238387D03*
X1235041D03*
X1231694D03*
X1228348D03*
X1225002D03*
X1221655D03*
X1265159Y41033D03*
X1261813D03*
X1258466D03*
X1255120D03*
X1251773D03*
X1248427D03*
X1245080D03*
X1241734D03*
X1238387D03*
X1235041D03*
X1231694D03*
X1228348D03*
X1225002D03*
X1221655D03*
X1265159Y523900D03*
X1261813D03*
X1258466D03*
X1255120D03*
X1251773D03*
X1248427D03*
X1245080D03*
X1241734D03*
X1238387D03*
X1235041D03*
X1231694D03*
X1228348D03*
X1225002D03*
X1221655D03*
X1265159Y579810D03*
X1261813D03*
X1258466D03*
X1255120D03*
X1251773D03*
X1248427D03*
X1245080D03*
X1241734D03*
X1238387D03*
X1235041D03*
X1231694D03*
X1228348D03*
X1225002D03*
X1221655D03*
X1265159Y561700D03*
X1261813D03*
X1258466D03*
X1255120D03*
X1251773D03*
X1248427D03*
X1245080D03*
X1241734D03*
X1238387D03*
X1235041D03*
X1231694D03*
X1228348D03*
X1225002D03*
X1221655D03*
X1265159Y542010D03*
X1261813D03*
X1258466D03*
X1255120D03*
X1251773D03*
X1248427D03*
X1245080D03*
X1241734D03*
X1238387D03*
X1235041D03*
X1231694D03*
X1228348D03*
X1225002D03*
X1221655D03*
X1265159Y617610D03*
X1261813D03*
X1258466D03*
X1255120D03*
X1251773D03*
X1248427D03*
X1245080D03*
X1241734D03*
X1238387D03*
X1235041D03*
X1231694D03*
X1228348D03*
X1225002D03*
X1221655D03*
X1265159Y599500D03*
X1261813D03*
X1258466D03*
X1255120D03*
X1251773D03*
X1248427D03*
X1245080D03*
X1241734D03*
X1238387D03*
X1235041D03*
X1231694D03*
X1228348D03*
X1225002D03*
X1221655D03*
G54D64*
X72800Y105000D03*
G54D247*
X1667012Y-14488D03*
G54D19*
X-13780Y598560D03*
X-3937Y-43307D03*
Y646063D03*
X1956693Y-43307D03*
Y646063D03*
G54D193*
X1430584Y467544D03*
G54D175*
X1370366Y72819D03*
X1563032Y106276D03*
X1576148Y115038D03*
X1648143Y177339D03*
X1610820Y223832D03*
X1678097Y164451D03*
G54D274*
X1860500Y80585D03*
G54D82*
X79477Y403180D03*
X100477D03*
X79473Y431271D03*
X100473D03*
X78900Y498750D03*
X57900D03*
X730000Y341500D03*
Y370500D03*
X751000Y341500D03*
Y370500D03*
X1392050Y61959D03*
X1413050D03*
G54D28*
X29654Y21862D03*
X29743Y52374D03*
X25000Y562500D03*
X20300Y529100D03*
X143700Y208300D03*
X147500Y272900D03*
X143700Y241000D03*
X144400Y306100D03*
X146209Y337400D03*
X144010Y369674D03*
X795699Y207600D03*
X799151Y240966D03*
X798387Y272898D03*
X795800Y336400D03*
X797570Y305000D03*
X792582Y368417D03*
G54D248*
X1707500Y121230D03*
G54D56*
X15187Y494150D03*
X13612D03*
X12037D03*
X10462D03*
X8887D03*
X7313D03*
X5738D03*
X4163D03*
X2588D03*
X1013D03*
X662163Y253350D03*
X660588D03*
X659013D03*
X673187D03*
X671612D03*
X670037D03*
X668462D03*
X666887D03*
X665313D03*
X663738D03*
X1364087Y50850D03*
X1362512D03*
X1360937D03*
X1359362D03*
X1357787D03*
X1356213D03*
X1354638D03*
X1353063D03*
X1351488D03*
X1349913D03*
G54D149*
X1251491Y327228D03*
G54D176*
X1360253Y214274D03*
X1371373Y211018D03*
G54D158*
X1279501Y350527D03*
G54D185*
X1446179Y95353D03*
Y90353D03*
Y85353D03*
Y80353D03*
Y75353D03*
Y70353D03*
X1445232Y153080D03*
Y143080D03*
Y148080D03*
X1446179Y105353D03*
Y100353D03*
X1445232Y173080D03*
Y168080D03*
Y158080D03*
Y163080D03*
Y178080D03*
X1483779Y75353D03*
Y80353D03*
Y85353D03*
Y90353D03*
Y95353D03*
Y70353D03*
X1482832Y143080D03*
Y153080D03*
Y148080D03*
X1483779Y105353D03*
Y100353D03*
X1482832Y168080D03*
Y163080D03*
Y158080D03*
Y173080D03*
Y178080D03*
X1529699Y195920D03*
Y200920D03*
Y205920D03*
Y210920D03*
Y215920D03*
Y190920D03*
Y185920D03*
Y220920D03*
X1567299Y190920D03*
Y195920D03*
Y210920D03*
Y205920D03*
Y200920D03*
Y185920D03*
Y215920D03*
Y220920D03*
X1599200Y207000D03*
Y217000D03*
Y212000D03*
X1620800D03*
Y207000D03*
Y202000D03*
X1599200D03*
X1620800Y217000D03*
G54D29*
X45012Y-10625D03*
X43437D03*
X41862D03*
X40287D03*
X38713D03*
X37138D03*
X35563D03*
X33988D03*
X32413D03*
X46587D03*
G54D167*
X1316231Y205501D03*
X1293820Y221977D03*
G54D284*
X1887327Y511202D03*
X1929453Y532541D03*
G54D38*
X42600Y35244D03*
X42500Y62500D03*
X33500Y580000D03*
X33100Y544100D03*
X71100Y35244D03*
X71000Y62500D03*
X62000Y580000D03*
X61600Y544100D03*
X157624Y224533D03*
Y256533D03*
Y288533D03*
Y320533D03*
Y384533D03*
Y352033D03*
X186124Y224533D03*
Y256533D03*
Y288533D03*
Y320533D03*
Y384533D03*
Y352033D03*
X645684Y212995D03*
X674184D03*
X835732Y256533D03*
X807232D03*
X835732Y224533D03*
X807232D03*
X835732Y288533D03*
X807232D03*
X835732Y320533D03*
X807232D03*
X835732Y351533D03*
X807232D03*
X835687Y383681D03*
X807187D03*
X1313516Y22624D03*
X1342016D03*
X1314216Y-7476D03*
X1342716D03*
X1315000Y387500D03*
X1343500D03*
X1315400Y580556D03*
X1343900D03*
X1315300Y609456D03*
X1343800D03*
X1513700Y577066D03*
X1542200D03*
G54D65*
X81500Y127000D03*
Y118000D03*
X95500Y127500D03*
Y118500D03*
X88500Y127000D03*
Y118000D03*
X1573000Y303500D03*
Y312500D03*
X1728000Y82000D03*
Y73000D03*
X1889000Y575700D03*
Y568300D03*
X1891560Y575700D03*
Y568300D03*
X1886440Y575700D03*
Y568300D03*
X1926400Y603700D03*
Y594700D03*
G54D293*
X1955426Y104548D03*
Y100612D03*
Y102580D03*
Y98644D03*
X1963526Y100612D03*
Y104548D03*
Y102580D03*
Y98644D03*
G54D74*
X52900Y290500D03*
Y283500D03*
X112600Y170300D03*
Y163300D03*
X655500Y19000D03*
Y12000D03*
X659950Y517400D03*
Y524400D03*
X653450Y517400D03*
Y524400D03*
X656099Y582993D03*
Y575993D03*
X721500Y59500D03*
Y52500D03*
X721900Y544100D03*
Y537100D03*
X729000Y52500D03*
Y59500D03*
X729600Y537150D03*
Y544150D03*
X1302500Y57400D03*
Y50400D03*
X1314367Y504500D03*
Y511500D03*
X1307767Y504500D03*
Y511500D03*
X1303000Y584500D03*
Y591500D03*
Y597500D03*
Y604500D03*
X1382000Y119500D03*
Y112500D03*
X1389700D03*
Y119500D03*
X1376500Y524500D03*
X1384500D03*
X1376500Y531500D03*
X1384500D03*
X1466950Y532550D03*
Y539550D03*
X1512000Y260100D03*
Y253100D03*
X1474350Y532350D03*
Y539350D03*
X1500850Y534200D03*
Y541200D03*
X1493350Y534200D03*
Y541200D03*
X1527440Y542300D03*
Y549300D03*
X1729700Y514000D03*
Y507000D03*
X1761700Y516900D03*
Y509900D03*
G54D239*
X1625951Y340193D03*
X1639055D03*
Y346099D03*
X1625951D03*
G54D83*
X67839Y375400D03*
X69413D03*
X70988D03*
X72563D03*
X74138D03*
X75713D03*
X77287D03*
X78862D03*
X80437D03*
X82012D03*
X83587D03*
X85161D03*
X716839Y286400D03*
X718413D03*
X719988D03*
X721563D03*
X723138D03*
X724713D03*
X726287D03*
X727862D03*
X729437D03*
X731012D03*
X732587D03*
X734161D03*
G54D92*
X170516Y149639D03*
Y182139D03*
X137907Y446215D03*
Y478715D03*
X782990Y154000D03*
Y121500D03*
X782984Y449000D03*
Y481500D03*
G54D266*
X1835832Y56368D03*
X1859768D03*
G54D275*
X1860500Y87800D03*
G54D47*
X48700Y250260D03*
X29000D03*
X48700Y261300D03*
X29000D03*
G54D257*
X1770080Y504930D03*
X1788580D03*
G54D194*
X1466733Y585953D03*
X1502030Y591554D03*
G54D57*
X-1550Y496713D03*
Y498288D03*
Y499863D03*
Y501438D03*
Y503013D03*
Y504587D03*
Y506162D03*
Y507737D03*
Y509312D03*
Y510887D03*
X656450Y255913D03*
Y257488D03*
Y259063D03*
Y260638D03*
Y262213D03*
Y263787D03*
Y265362D03*
Y266937D03*
Y268512D03*
Y270087D03*
X1347350Y53413D03*
Y54988D03*
Y56563D03*
Y58138D03*
Y59713D03*
Y61287D03*
Y62862D03*
Y64437D03*
Y66012D03*
Y67587D03*
G54D249*
X1698611Y192179D03*
Y183518D03*
X1692312D03*
Y192179D03*
G54D168*
X1303646Y199358D03*
G54D39*
X21100Y16000D03*
X22292Y503187D03*
X417190Y112652D03*
X383938Y103754D03*
X422606Y116393D03*
X454520Y104627D03*
X1033546Y103754D03*
X1066798Y112652D03*
X1104128Y104627D03*
X1101598Y110917D03*
X1109228Y123800D03*
G54D177*
X1382500Y381270D03*
X1437930Y459805D03*
X1429229Y548455D03*
G54D66*
X72900Y168118D03*
X79900Y165559D03*
Y163000D03*
X72900D03*
X79900Y168118D03*
X104250Y327382D03*
X97250Y332500D03*
Y329941D03*
X104250Y332500D03*
X97250Y327382D03*
X652230Y485130D03*
Y487690D03*
X645230Y485130D03*
Y490250D03*
Y487690D03*
X652230Y490250D03*
X685268Y288147D03*
Y290706D03*
Y285588D03*
X678268D03*
Y288147D03*
Y290706D03*
X1446800Y368018D03*
X1453800Y362900D03*
Y365459D03*
X1446800Y362900D03*
X1453800Y368018D03*
X1528513Y322534D03*
X1521513Y325093D03*
Y327652D03*
X1528513D03*
X1521513Y322534D03*
X1646378Y202515D03*
Y205074D03*
X1639378Y202515D03*
Y207633D03*
Y205074D03*
X1646378Y207633D03*
X1649500Y329059D03*
Y326500D03*
Y323941D03*
Y318559D03*
Y313441D03*
X1656500Y323941D03*
Y329059D03*
Y316000D03*
Y318559D03*
Y313441D03*
X1737814Y576682D03*
Y571564D03*
X1730814D03*
Y574123D03*
Y576682D03*
X1828874Y-5980D03*
Y-8540D03*
X1835874Y-5980D03*
Y-11100D03*
Y-8540D03*
X1828874Y-11100D03*
X1793000Y130059D03*
X1800000Y127500D03*
X1793000Y124941D03*
X1800000Y130059D03*
Y124941D03*
X1788500Y620500D03*
X1795500D03*
X1788500Y617941D03*
X1795500Y615382D03*
X1788500D03*
X1795500Y617941D03*
X1911000Y546341D03*
Y548900D03*
Y543782D03*
X1904000D03*
Y546341D03*
Y548900D03*
G54D75*
X63382Y325500D03*
X65941D03*
X63382Y332500D03*
X68500D03*
X65941D03*
X68500Y325500D03*
X679430Y492970D03*
X681990D03*
X679430Y499970D03*
X684550D03*
X681990D03*
X684550Y492970D03*
X1510987Y325669D03*
X1508428Y318669D03*
X1505869D03*
Y325669D03*
X1510987Y318669D03*
X1581941Y326000D03*
X1584500Y333000D03*
X1587059Y326000D03*
X1581941Y333000D03*
X1587059D03*
X1634882Y217000D03*
X1640000D03*
Y224000D03*
X1637441D03*
X1634882D03*
X1699941Y77668D03*
X1702500Y84668D03*
X1705059Y77668D03*
X1699941Y84668D03*
X1705059D03*
X1763118Y58000D03*
X1760559Y51000D03*
X1758000Y58000D03*
X1763118Y51000D03*
X1758000D03*
X1798055Y143789D03*
X1795495D03*
X1798055Y136789D03*
X1792935D03*
X1795495D03*
X1792935Y143789D03*
X1801070Y115000D03*
X1798510D03*
X1801070Y108000D03*
X1795950D03*
X1798510D03*
X1795950Y115000D03*
X1836000Y539500D03*
Y546500D03*
X1876070Y552500D03*
X1873510D03*
X1876070Y545500D03*
X1870950D03*
X1873510D03*
X1870950Y552500D03*
X1841118Y546500D03*
X1838559Y539500D03*
X1841118D03*
X1925803Y578500D03*
X1928362Y585500D03*
X1930921Y578500D03*
X1925803Y585500D03*
X1930921D03*
G54D258*
X1719500Y494500D03*
G54D84*
X87900Y372661D03*
Y371087D03*
Y369512D03*
Y367937D03*
Y366362D03*
Y364787D03*
Y363213D03*
Y361638D03*
Y360063D03*
Y358488D03*
Y356913D03*
Y355339D03*
X736900Y278937D03*
Y277362D03*
Y275787D03*
Y274213D03*
Y272638D03*
Y271063D03*
Y269488D03*
Y267913D03*
Y266339D03*
Y283661D03*
Y282087D03*
Y280512D03*
G54D159*
X1260765Y451319D03*
X1253522Y445355D03*
G54D267*
X1787000Y135500D03*
Y143500D03*
X1882660Y540663D03*
X1890660D03*
X1905100Y538000D03*
X1913100D03*
G54D195*
X1404910Y536868D03*
Y538443D03*
Y540018D03*
Y541593D03*
Y543168D03*
Y544742D03*
Y546317D03*
Y547892D03*
Y549467D03*
Y551042D03*
X1548550Y598413D03*
Y599988D03*
Y601563D03*
Y603138D03*
Y604713D03*
Y606287D03*
Y607862D03*
Y609437D03*
Y611012D03*
Y612587D03*
G54D276*
X1856354Y84433D03*
Y96430D03*
G54D285*
X1892720Y525415D03*
X1900595D03*
X1908469D03*
X1916343D03*
X1924217D03*
X1922248Y518328D03*
X1912406D03*
X1904532D03*
G54D186*
X1456476Y278327D03*
X1443878Y268878D03*
X1453327Y278327D03*
X1450177Y275177D03*
X1447028Y272028D03*
X1453327Y275177D03*
Y268878D03*
X1447028D03*
X1450177Y272028D03*
X1456476D03*
Y275177D03*
X1450177Y268878D03*
X1453327Y272028D03*
X1456476Y268878D03*
X1459626Y272028D03*
Y278327D03*
Y275177D03*
Y268878D03*
X1462776Y272028D03*
Y275177D03*
Y278327D03*
Y268878D03*
X1447028Y278327D03*
X1443878Y275177D03*
Y278327D03*
Y272028D03*
X1447028Y275177D03*
X1450177Y278327D03*
X1456476Y306673D03*
X1453327Y303524D03*
X1462776Y294075D03*
Y290925D03*
X1453327Y281476D03*
X1462776Y297224D03*
Y287776D03*
X1443878Y316122D03*
X1459626Y284626D03*
X1456476Y281476D03*
X1447028Y312972D03*
X1450177Y309823D03*
X1453327Y306673D03*
X1456476Y303524D03*
X1459626Y300374D03*
X1462776Y284626D03*
Y281476D03*
X1459626D03*
X1453327Y294075D03*
X1459626Y290925D03*
X1443878Y297224D03*
X1447028Y294075D03*
X1450177D03*
X1443878D03*
Y290925D03*
X1450177D03*
X1456476Y294075D03*
X1453327Y290925D03*
X1447028D03*
X1443878Y287776D03*
X1456476Y290925D03*
X1459626Y287776D03*
X1450177D03*
X1447028D03*
X1453327D03*
X1456476Y284626D03*
X1443878D03*
X1450177D03*
X1456476Y287776D03*
X1453327Y284626D03*
X1447028D03*
X1443878Y281476D03*
X1450177D03*
X1447028D03*
X1443878Y312972D03*
X1447028Y309823D03*
X1450177Y306673D03*
X1443878D03*
Y309823D03*
X1447028Y306673D03*
Y303524D03*
X1450177D03*
X1453327Y300374D03*
X1459626Y297224D03*
X1443878Y303524D03*
X1447028Y300374D03*
X1456476Y297224D03*
X1453327D03*
X1450177Y300374D03*
X1443878D03*
X1456476D03*
X1459626Y294075D03*
X1447028Y297224D03*
X1450177D03*
Y312972D03*
X1447028Y316122D03*
X1453327Y309823D03*
X1456476Y312972D03*
X1453327Y316122D03*
X1456476Y309823D03*
X1450177Y316122D03*
X1453327Y312972D03*
X1456476Y316122D03*
X1459626Y312972D03*
Y306673D03*
X1462776Y303524D03*
X1459626Y309823D03*
Y316122D03*
Y303524D03*
X1462776Y306673D03*
Y312972D03*
Y309823D03*
Y300374D03*
Y316122D03*
X1478524Y278327D03*
X1491122Y268878D03*
X1487972D03*
X1481673Y278327D03*
X1484823Y275177D03*
X1487972Y272028D03*
X1484823D03*
X1478524D03*
X1481673Y275177D03*
X1465925Y272028D03*
Y275177D03*
Y268878D03*
Y278327D03*
X1469075D03*
Y268878D03*
Y275177D03*
Y272028D03*
X1472224Y268878D03*
Y278327D03*
Y275177D03*
Y272028D03*
X1475374Y268878D03*
Y275177D03*
Y278327D03*
X1481673Y272028D03*
X1484823Y268878D03*
X1475374Y272028D03*
X1478524Y268878D03*
Y275177D03*
X1481673Y268878D03*
X1487972Y278327D03*
X1491122Y275177D03*
X1487972D03*
X1491122Y272028D03*
Y278327D03*
X1484823D03*
X1481673Y281476D03*
X1472224Y290925D03*
Y294075D03*
X1481673Y303524D03*
X1478524Y306673D03*
X1469075Y297224D03*
X1465925D03*
Y287776D03*
X1469075D03*
X1472224Y297224D03*
Y287776D03*
X1491122Y316122D03*
X1475374Y284626D03*
X1478524Y281476D03*
X1487972Y312972D03*
X1484823Y309823D03*
X1481673Y306673D03*
X1478524Y303524D03*
X1475374Y300374D03*
X1465925Y294075D03*
X1469075D03*
X1465925Y290925D03*
X1469075D03*
X1465925Y284626D03*
X1469075D03*
X1465925Y281476D03*
X1469075D03*
X1472224Y284626D03*
X1475374Y281476D03*
X1472224D03*
X1481673Y294075D03*
X1478524Y290925D03*
X1491122Y297224D03*
X1487972Y294075D03*
X1484823D03*
X1491122D03*
Y290925D03*
X1484823D03*
X1475374Y294075D03*
X1481673Y290925D03*
X1487972D03*
X1491122Y287776D03*
X1475374Y290925D03*
X1478524Y284626D03*
X1484823Y287776D03*
X1487972D03*
X1481673D03*
X1478524D03*
X1491122Y284626D03*
X1484823D03*
X1475374Y287776D03*
X1481673Y284626D03*
X1487972D03*
X1491122Y281476D03*
X1484823D03*
X1487972D03*
Y309823D03*
X1491122Y312972D03*
X1484823Y306673D03*
X1487972Y303524D03*
X1491122Y309823D03*
X1487972Y306673D03*
X1491122D03*
X1484823Y303524D03*
X1481673Y300374D03*
X1478524Y297224D03*
X1491122Y303524D03*
X1487972Y300374D03*
X1478524D03*
X1481673Y297224D03*
X1484823Y300374D03*
X1491122D03*
X1475374Y297224D03*
X1478524Y294075D03*
X1487972Y297224D03*
X1484823D03*
X1472224Y306673D03*
Y303524D03*
Y309823D03*
Y312972D03*
Y300374D03*
X1475374Y306673D03*
Y316122D03*
Y309823D03*
X1481673Y312972D03*
X1484823Y316122D03*
X1475374Y312972D03*
X1478524Y316122D03*
Y309823D03*
Y312972D03*
X1484823D03*
X1487972Y316122D03*
X1481673D03*
Y309823D03*
X1465925Y303524D03*
Y312972D03*
Y306673D03*
X1469075Y303524D03*
X1465925Y309823D03*
Y316122D03*
Y300374D03*
X1469075Y306673D03*
Y316122D03*
Y309823D03*
Y300374D03*
X1475374Y303524D03*
X1469075Y312972D03*
X1472224Y316122D03*
X1517075Y443525D03*
X1523375Y446675D03*
X1520225Y449825D03*
X1505073Y412220D03*
Y452780D03*
X1507625Y443525D03*
Y415175D03*
Y452975D03*
X1510775Y412025D03*
Y415175D03*
Y443525D03*
Y452975D03*
X1513925Y446675D03*
Y415175D03*
Y443525D03*
Y449825D03*
Y452975D03*
X1517075Y418325D03*
Y452975D03*
X1520225Y412025D03*
Y421475D03*
Y440375D03*
Y443525D03*
X1523375Y424625D03*
X1526525Y421475D03*
X1523375Y412025D03*
Y421475D03*
Y427775D03*
Y430925D03*
Y434075D03*
Y437225D03*
Y440375D03*
X1526525Y412025D03*
Y440375D03*
Y449825D03*
Y452975D03*
Y430925D03*
X1505075Y432500D03*
X1526525Y424625D03*
X1505075Y418980D03*
Y425740D03*
Y439260D03*
X1507625Y418325D03*
Y421475D03*
Y424625D03*
Y427775D03*
Y430925D03*
Y434075D03*
Y437225D03*
Y440375D03*
X1510775Y418325D03*
Y421475D03*
Y424625D03*
Y427775D03*
Y430925D03*
Y434075D03*
Y437225D03*
Y440375D03*
X1513925Y418325D03*
Y421475D03*
Y424625D03*
Y427775D03*
Y430925D03*
Y434075D03*
Y437225D03*
Y440375D03*
X1517075Y421475D03*
Y424625D03*
Y427775D03*
Y430925D03*
Y434075D03*
Y437225D03*
Y440375D03*
X1520225Y424625D03*
Y427775D03*
Y430925D03*
Y434075D03*
Y437225D03*
X1526525Y427775D03*
Y434075D03*
Y437225D03*
X1517075Y415175D03*
Y412025D03*
X1526525Y418325D03*
X1520225D03*
X1523375Y415175D03*
X1510775Y446675D03*
Y449825D03*
X1513925Y412025D03*
X1523375Y418325D03*
X1507625Y412025D03*
X1526525Y415175D03*
X1505075Y446020D03*
X1507625Y446675D03*
Y449825D03*
X1520225Y415175D03*
X1523375Y443525D03*
X1526525D03*
Y446675D03*
X1520225Y452975D03*
X1517075Y446675D03*
Y449825D03*
X1523375Y452975D03*
Y449825D03*
X1520225Y446675D03*
X1529675Y412025D03*
Y421475D03*
Y440375D03*
Y449825D03*
X1532825Y412025D03*
Y421475D03*
Y440375D03*
Y449825D03*
X1535975Y412025D03*
Y421475D03*
Y440375D03*
Y449825D03*
X1539125Y412025D03*
Y421475D03*
Y440375D03*
Y449825D03*
X1542275Y412025D03*
Y421475D03*
Y424625D03*
Y427775D03*
Y430925D03*
Y434075D03*
Y437225D03*
Y440375D03*
Y449825D03*
X1547975Y446020D03*
X1547977Y452780D03*
X1535975Y434075D03*
X1532825Y427775D03*
Y430925D03*
Y434075D03*
Y437225D03*
X1535975Y424625D03*
Y427775D03*
Y430925D03*
X1539125Y424625D03*
Y427775D03*
X1529675Y424625D03*
Y427775D03*
Y430925D03*
Y434075D03*
Y437225D03*
X1532825Y424625D03*
X1539125Y430925D03*
X1529675Y452975D03*
X1532825D03*
X1539125D03*
X1535975D03*
X1542275D03*
X1545425Y446675D03*
Y449825D03*
Y452975D03*
X1529675Y415175D03*
X1535975Y437225D03*
X1539125Y434075D03*
Y437225D03*
X1542275Y415175D03*
X1532825Y418325D03*
X1529675D03*
X1535975D03*
X1542275D03*
X1539125D03*
X1547977Y412220D03*
X1545425Y412025D03*
X1539125Y415175D03*
X1545425Y443525D03*
Y421475D03*
Y424625D03*
Y427775D03*
Y430925D03*
Y434075D03*
X1547975Y425740D03*
Y432500D03*
X1545425Y415175D03*
Y418325D03*
Y437225D03*
Y440375D03*
X1547975Y439260D03*
X1529675Y446675D03*
X1532825Y443525D03*
Y446675D03*
X1535975Y443525D03*
Y446675D03*
X1539125Y443525D03*
Y446675D03*
X1542275Y443525D03*
X1529675D03*
X1542275Y446675D03*
X1535975Y415175D03*
X1532825D03*
X1547975Y418980D03*
X1624764Y123365D03*
X1627914D03*
X1634213Y120215D03*
Y117066D03*
X1618465Y126514D03*
Y123365D03*
Y135963D03*
Y132814D03*
X1643662Y154861D03*
X1640512Y120215D03*
Y154861D03*
X1631064Y123365D03*
X1624764Y154861D03*
X1621615Y151711D03*
X1618465Y148562D03*
Y145412D03*
Y142262D03*
X1649961Y148562D03*
X1646812Y120215D03*
Y154861D03*
X1643662Y120215D03*
X1618465Y139113D03*
X1634213Y151711D03*
Y154861D03*
X1649961Y126514D03*
Y145412D03*
Y142262D03*
Y139113D03*
Y132814D03*
Y135963D03*
X1631064Y154861D03*
X1627914D03*
X1621615Y129664D03*
Y126514D03*
Y123365D03*
Y148562D03*
Y145412D03*
Y142262D03*
Y139113D03*
Y135963D03*
X1646812Y123365D03*
Y151711D03*
X1643662Y129664D03*
Y123365D03*
Y151711D03*
X1621615Y132814D03*
X1643662Y145412D03*
Y142262D03*
Y139113D03*
Y135963D03*
Y132814D03*
X1640512Y123365D03*
Y151711D03*
X1634213Y123365D03*
X1627914Y151711D03*
X1624764D03*
X1618465Y120215D03*
X1609016D03*
X1615316Y117066D03*
X1649961Y123365D03*
Y120215D03*
Y151711D03*
X1640512Y129664D03*
Y145412D03*
Y142262D03*
Y139113D03*
Y135963D03*
Y132814D03*
X1637363Y129664D03*
Y123365D03*
Y120215D03*
Y117066D03*
Y113916D03*
Y110766D03*
Y107617D03*
Y154861D03*
Y151711D03*
Y145412D03*
Y142262D03*
Y139113D03*
Y135963D03*
Y132814D03*
Y104467D03*
X1634213Y129664D03*
Y145412D03*
Y142262D03*
Y139113D03*
Y135963D03*
Y132814D03*
X1631064Y129664D03*
Y151711D03*
Y145412D03*
Y142262D03*
Y139113D03*
Y135963D03*
Y132814D03*
X1627914Y129664D03*
Y117066D03*
Y145412D03*
Y142262D03*
Y139113D03*
Y135963D03*
Y132814D03*
X1624764Y120215D03*
X1621615D03*
X1618465Y151711D03*
X1615316Y126514D03*
X1631064Y113916D03*
Y117066D03*
Y120215D03*
X1615316Y113916D03*
X1624764Y107617D03*
Y104467D03*
X1627914D03*
Y120215D03*
X1605867D03*
X1602717D03*
X1605867Y123365D03*
X1602717D03*
Y126514D03*
X1605867D03*
X1609016Y123365D03*
Y126514D03*
X1612166Y135963D03*
Y139113D03*
X1609016Y132814D03*
Y129664D03*
X1615316Y135963D03*
X1649961Y113916D03*
Y110766D03*
X1646812D03*
Y113916D03*
X1640512Y117066D03*
Y113916D03*
Y110766D03*
X1634213Y107617D03*
X1646812D03*
X1602717Y148562D03*
Y145412D03*
X1609016Y148562D03*
X1605867D03*
X1609016Y151711D03*
X1605867D03*
X1615316Y148562D03*
Y145412D03*
X1612166Y148562D03*
Y151711D03*
X1615316Y154861D03*
Y151711D03*
X1631064Y110766D03*
X1627914Y113916D03*
Y110766D03*
Y107617D03*
X1621615Y110766D03*
X1618465Y107617D03*
X1621615Y113916D03*
Y117066D03*
X1615316Y110766D03*
X1618465D03*
X1615316Y104467D03*
Y107617D03*
X1618465Y117066D03*
X1624764Y113916D03*
Y110766D03*
X1621615Y104467D03*
X1624764Y117066D03*
X1618465Y104467D03*
X1621615Y107617D03*
X1618465Y113916D03*
X1631064Y104467D03*
Y107617D03*
X1612166Y110766D03*
Y113916D03*
Y117066D03*
X1615316Y120215D03*
X1612166Y107617D03*
Y104467D03*
Y123365D03*
X1615316D03*
X1602717Y117066D03*
X1618465Y129664D03*
X1615316D03*
X1605867Y117066D03*
X1609016Y113916D03*
Y117066D03*
X1612166Y120215D03*
X1602717Y113916D03*
X1605867D03*
X1615316Y132814D03*
X1612166Y126514D03*
X1649961Y154861D03*
Y117066D03*
X1646812D03*
X1643662D03*
Y110766D03*
Y113916D03*
X1649961Y104467D03*
Y107617D03*
X1602717Y151711D03*
X1605867Y154861D03*
X1602717D03*
X1609016D03*
X1612166D03*
X1621615D03*
X1618465D03*
X1605867Y142262D03*
X1609016D03*
X1649961Y129664D03*
X1605867Y132814D03*
Y129664D03*
X1602717D03*
Y132814D03*
Y135963D03*
X1646812Y104467D03*
X1643662Y107617D03*
Y104467D03*
X1640512D03*
Y107617D03*
X1634213Y104467D03*
Y113916D03*
Y110766D03*
X1605867Y135963D03*
X1609016D03*
X1615316Y139113D03*
X1612166Y132814D03*
Y129664D03*
X1605867Y139113D03*
X1602717D03*
X1609016D03*
X1602717Y142262D03*
X1609016Y145412D03*
X1615316Y142262D03*
X1612166D03*
Y145412D03*
X1605867D03*
X1627914Y170609D03*
Y167459D03*
X1621615Y161160D03*
X1609016Y158010D03*
Y161160D03*
X1615316D03*
X1602717D03*
X1643662Y167459D03*
Y170609D03*
X1646812Y167459D03*
Y170609D03*
Y161160D03*
X1643662Y158010D03*
X1646812D03*
X1649961Y161160D03*
X1612166Y158010D03*
X1605867D03*
X1602717D03*
X1624764D03*
Y161160D03*
X1627914Y158010D03*
Y161160D03*
X1605867D03*
X1612166D03*
X1615316Y158010D03*
X1618465D03*
X1646812Y164310D03*
X1649961Y170609D03*
Y167459D03*
X1640512Y161160D03*
X1643662D03*
X1640512Y158010D03*
X1649961Y164310D03*
Y158010D03*
X1634213Y167459D03*
Y170609D03*
X1637363Y167459D03*
Y170609D03*
X1634213Y164310D03*
X1631064D03*
Y167459D03*
Y170609D03*
X1643662Y164310D03*
X1637363D03*
Y161160D03*
Y158010D03*
X1640512Y164310D03*
Y170609D03*
Y167459D03*
X1621615Y158010D03*
X1615316Y164310D03*
X1612166Y167459D03*
Y164310D03*
X1618465D03*
X1615316Y167459D03*
X1618465Y161160D03*
X1624764Y164310D03*
Y170609D03*
Y167459D03*
X1627914Y164310D03*
X1631064Y158010D03*
X1634213D03*
Y161160D03*
X1631064D03*
X1621615Y170609D03*
X1618465D03*
Y167459D03*
X1615316Y170609D03*
X1612166D03*
X1621615Y164310D03*
Y167459D03*
X1656260Y154861D03*
X1662560D03*
X1659410D03*
X1665709Y129664D03*
X1656260Y126514D03*
Y151711D03*
Y145412D03*
Y139113D03*
Y132814D03*
X1653111Y120215D03*
Y135963D03*
X1665709Y123365D03*
Y148562D03*
Y142262D03*
Y135963D03*
Y154861D03*
X1656260Y120215D03*
X1659410D03*
X1662560Y117066D03*
Y120215D03*
X1668859Y117066D03*
X1665709D03*
X1659410D03*
X1656260Y113916D03*
X1659410D03*
X1665709D03*
X1662560D03*
X1668859D03*
X1656260Y117066D03*
X1653111Y113916D03*
Y117066D03*
X1659410Y110766D03*
X1653111D03*
X1656260D03*
X1659410Y107617D03*
X1656260D03*
X1659410Y104467D03*
X1656260D03*
X1653111Y107617D03*
Y104467D03*
Y154861D03*
X1662560Y139113D03*
X1668859Y154861D03*
X1659410Y139113D03*
X1656260Y135963D03*
X1659410D03*
X1668859Y120215D03*
Y123365D03*
Y132814D03*
Y129664D03*
X1662560Y126514D03*
X1665709D03*
X1656260Y129664D03*
X1659410D03*
X1662560D03*
X1653111D03*
X1665709Y132814D03*
X1662560D03*
X1653111Y123365D03*
X1656260D03*
X1659410D03*
X1665709Y120215D03*
X1659410Y126514D03*
X1662560Y123365D03*
X1659410Y132814D03*
X1653111D03*
X1668859Y126514D03*
X1653111D03*
X1665709Y139113D03*
X1662560Y135963D03*
X1668859Y139113D03*
Y135963D03*
Y142262D03*
X1659410D03*
X1662560D03*
X1653111Y139113D03*
Y151711D03*
X1662560D03*
X1659410D03*
X1665709D03*
X1668859D03*
X1656260Y148562D03*
X1659410D03*
X1653111Y145412D03*
X1659410D03*
X1653111Y148562D03*
X1662560D03*
X1668859D03*
X1662560Y145412D03*
X1665709D03*
X1653111Y142262D03*
X1668859Y145412D03*
X1656260Y142262D03*
X1653111Y158010D03*
X1668859D03*
X1662560D03*
X1656260D03*
X1659410D03*
Y167459D03*
X1656260Y170609D03*
X1659410D03*
X1653111Y167459D03*
Y164310D03*
X1659410D03*
X1653111Y161160D03*
X1656260Y164310D03*
Y161160D03*
X1659410D03*
X1662560D03*
X1665709D03*
X1653111Y170609D03*
X1656260Y167459D03*
X1668859Y161160D03*
X1665709Y158010D03*
X1718591Y115876D03*
X1740638Y131624D03*
X1718591Y122175D03*
X1743787D03*
Y115876D03*
X1721740Y112726D03*
X1737488D03*
X1721740Y109577D03*
X1740638D03*
X1718591Y106427D03*
X1721740Y100128D03*
X1740638D03*
X1743787Y147372D03*
Y137923D03*
X1718591Y134774D03*
Y128474D03*
X1743787D03*
X1721740Y119026D03*
X1718591Y112726D03*
X1743787D03*
X1740638Y103278D03*
X1743787Y134774D03*
X1718591Y144222D03*
X1743787Y103278D03*
X1721740Y125325D03*
X1740638D03*
X1718591Y119026D03*
X1743787D03*
X1721740Y115876D03*
X1740638D03*
X1718591Y109577D03*
X1743787Y106427D03*
X1718591Y100128D03*
X1743787D03*
X1718591Y147372D03*
X1743787Y144222D03*
X1718591Y131624D03*
X1743787D03*
X1718591Y125325D03*
X1743787D03*
X1724890Y119026D03*
X1743787Y109577D03*
X1718591Y103278D03*
X1737488D03*
X1718591Y137923D03*
X1743787Y141073D03*
X1721740Y131624D03*
X1737488Y147372D03*
Y128474D03*
X1724890Y147372D03*
Y109577D03*
X1737488D03*
X1721740Y106427D03*
X1740638D03*
X1724890D03*
X1737488D03*
X1721740Y103278D03*
X1737488Y100128D03*
X1724890Y103278D03*
Y100128D03*
X1737488Y119026D03*
Y115876D03*
X1724890Y125325D03*
X1737488D03*
X1721740Y122175D03*
X1740638D03*
X1724890D03*
X1737488D03*
X1724890Y115876D03*
X1740638Y119026D03*
Y112726D03*
X1724890D03*
Y131624D03*
Y128474D03*
X1721740D03*
X1740638D03*
X1721740Y134774D03*
X1740638D03*
X1721740Y137923D03*
X1740638D03*
X1718591Y141073D03*
X1737488Y131624D03*
X1724890Y144222D03*
X1740638D03*
X1721740D03*
X1740638Y141073D03*
X1721740D03*
X1737488Y137923D03*
X1724890D03*
X1737488Y144222D03*
X1721740Y147372D03*
X1724890Y134774D03*
X1740638Y147372D03*
X1737488Y134774D03*
X1724890Y141073D03*
X1737488D03*
G54D294*
X1933849Y132626D03*
Y134594D03*
Y138531D03*
Y140500D03*
X1931550Y132626D03*
Y134594D03*
Y138531D03*
Y140500D03*
G54D48*
X48700Y255780D03*
X29000D03*
G54D93*
X149920Y137452D03*
Y108452D03*
G54D58*
X1013Y513450D03*
X2588D03*
X4163D03*
X5738D03*
X7313D03*
X8887D03*
X10462D03*
X12037D03*
X13612D03*
X15187D03*
X659013Y272650D03*
X660588D03*
X662163D03*
X663738D03*
X665313D03*
X666887D03*
X668462D03*
X670037D03*
X671612D03*
X673187D03*
X1349913Y70150D03*
X1351488D03*
X1353063D03*
X1354638D03*
X1356213D03*
X1357787D03*
X1359362D03*
X1360937D03*
X1362512D03*
X1364087D03*
G54D76*
X94973Y341879D03*
X98590Y371450D03*
X98540Y356360D03*
X98563Y348771D03*
X98520Y363880D03*
X96528Y387642D03*
X744020Y258770D03*
X750900Y264100D03*
X751700Y276900D03*
X745200Y270500D03*
X745400Y281900D03*
X1359512Y45934D03*
G54D187*
X1432543Y291443D03*
G54D169*
X1296586Y198653D03*
X1286850Y207463D03*
G54D277*
X1889906Y96662D03*
X1900406D03*
G54D295*
X1932700Y136563D03*
G54D259*
X1719500Y499620D03*
G54D94*
X111093Y122603D03*
X118935D03*
Y126345D03*
Y118861D03*
X111093D03*
Y126345D03*
X718916Y92446D03*
X711074D03*
Y96188D03*
X718916D03*
Y99930D03*
X711074D03*
X727916Y499895D03*
X735758D03*
Y503637D03*
Y496153D03*
X727916D03*
Y503637D03*
G54D268*
X1791000Y115500D03*
Y108500D03*
G54D85*
X85161Y352600D03*
X83587D03*
X82012D03*
X80437D03*
X78862D03*
X77287D03*
X75713D03*
X74138D03*
X72563D03*
X70988D03*
X69413D03*
X67839D03*
X724713Y263600D03*
X723138D03*
X721563D03*
X719988D03*
X718413D03*
X716839D03*
X734161D03*
X732587D03*
X731012D03*
X729437D03*
X727862D03*
X726287D03*
G54D196*
X1407473Y553605D03*
X1409048D03*
X1410623D03*
X1412198D03*
X1413773D03*
X1415347D03*
X1416922D03*
X1418497D03*
X1420072D03*
X1421647D03*
X1551113Y615150D03*
X1552688D03*
X1554263D03*
X1555838D03*
X1557413D03*
X1558987D03*
X1560562D03*
X1562137D03*
X1563712D03*
X1565287D03*
G54D286*
X1894689Y518328D03*
G54D178*
X1391987Y482515D03*
X1404310Y492405D03*
G54D49*
X10512Y467244D03*
X20512D03*
X30512D03*
X40512D03*
X50512D03*
X1884100Y493000D03*
X1894100D03*
X1891086Y612105D03*
Y602105D03*
G54D67*
X101200Y177500D03*
Y198500D03*
X746000Y202000D03*
Y223000D03*
G54D77*
X94973Y338279D03*
X98590Y367850D03*
X98540Y352760D03*
X98563Y345171D03*
X98520Y360280D03*
X96528Y384042D03*
X744020Y255170D03*
X750900Y260500D03*
X745400Y278300D03*
X751700Y273300D03*
X745200Y266900D03*
X1359512Y42334D03*
G54D179*
X1351800Y491619D03*
X1565079Y129375D03*
X1628655Y424800D03*
X1642515D03*
X1702140Y146363D03*
X1691776Y144438D03*
X1701890Y113250D03*
X1695119Y111254D03*
X1760339Y153550D03*
X1758228Y148550D03*
X1759589Y138950D03*
X1763217Y134550D03*
X1760240Y130050D03*
X1761298Y143850D03*
X1756589Y121000D03*
G54D188*
X1446500Y382000D03*
Y394000D03*
G54D59*
X-6660Y499300D03*
X-11685Y495700D03*
X-11202Y516700D03*
X-6410Y546789D03*
X72131Y348000D03*
X117300Y259500D03*
X116442Y296473D03*
X117320Y291322D03*
X117352Y323322D03*
G54D68*
X83000Y257700D03*
Y252700D03*
Y247700D03*
Y262700D03*
X83553Y234800D03*
Y229800D03*
Y224800D03*
Y239800D03*
G54D296*
X1955531Y155984D03*
Y152047D03*
Y148110D03*
Y144173D03*
Y175669D03*
Y171732D03*
Y167795D03*
Y163858D03*
Y159921D03*
Y191417D03*
Y187480D03*
Y183543D03*
Y179606D03*
G54D269*
X1822758Y542204D03*
X1800207Y540236D03*
X1822758D03*
X1800207Y538267D03*
X1800206Y587480D03*
X1822757D03*
X1800206Y585511D03*
X1822757D03*
X1800206Y583543D03*
X1822757D03*
X1800206Y581574D03*
X1822758Y538267D03*
X1822757Y581574D03*
X1800206Y579606D03*
X1822757D03*
X1800206Y577637D03*
X1822757D03*
X1800206Y575669D03*
X1822757D03*
X1800206Y573700D03*
X1822757D03*
X1800206Y571732D03*
X1800207Y536299D03*
X1822757Y571732D03*
X1800206Y569763D03*
X1822757D03*
X1800206Y567795D03*
X1822757D03*
X1800206Y565826D03*
X1822757D03*
X1800206Y563858D03*
X1822757D03*
X1800207Y561889D03*
X1822758Y536299D03*
Y561889D03*
X1800207Y559921D03*
X1822758D03*
X1800207Y557952D03*
X1822758D03*
X1800207Y555984D03*
X1822758D03*
X1800207Y554015D03*
X1822758D03*
X1800207Y552047D03*
Y534330D03*
X1822758Y552047D03*
X1800207Y550078D03*
X1822758D03*
X1800207Y548110D03*
X1822758D03*
X1800207Y546141D03*
X1822758D03*
X1800207Y544173D03*
X1822758D03*
X1800207Y542204D03*
X1822758Y534330D03*
X1800206Y591417D03*
X1822757D03*
X1800206Y589448D03*
X1822757D03*
G54D278*
X1861735Y96422D03*
G54D197*
X1424210Y551042D03*
Y549467D03*
Y547892D03*
Y546317D03*
Y544742D03*
Y543168D03*
Y541593D03*
Y540018D03*
Y538443D03*
Y536868D03*
X1567850Y612587D03*
Y611012D03*
Y609437D03*
Y607862D03*
Y606287D03*
Y604713D03*
Y603138D03*
Y601563D03*
Y599988D03*
Y598413D03*
G54D86*
X65100Y355339D03*
Y356913D03*
Y358488D03*
Y360063D03*
Y361638D03*
Y363213D03*
Y364787D03*
Y366362D03*
Y367937D03*
Y369512D03*
Y371087D03*
Y372661D03*
X714100Y266339D03*
Y267913D03*
Y269488D03*
Y271063D03*
Y272638D03*
Y274213D03*
Y275787D03*
Y277362D03*
Y278937D03*
Y280512D03*
Y282087D03*
Y283661D03*
G54D95*
X199221Y111179D03*
X317912Y108520D03*
X324046Y108154D03*
X353842Y114416D03*
X370193Y114952D03*
X361803Y113813D03*
X406851Y492615D03*
X418874Y498682D03*
X427596Y494704D03*
X419651Y492659D03*
X832370Y160129D03*
X967478Y108478D03*
X972825Y107325D03*
X951175Y122825D03*
X1019801Y114952D03*
X1011411Y113813D03*
X1004250Y115216D03*
X1248531Y115203D03*
G54D287*
X1851504Y497504D03*
X1868204Y505378D03*
X1851504D03*
X1868204Y513252D03*
X1851504D03*
X1868204Y521126D03*
X1851504D03*
X1868204Y497504D03*
Y529000D03*
X1851504D03*
G54D279*
X1893750Y130360D03*
Y128390D03*
Y120510D03*
Y114600D03*
Y112630D03*
Y126420D03*
Y118540D03*
Y116570D03*
Y124450D03*
Y122480D03*
G54D288*
X1887327Y532541D03*
X1929453Y511202D03*
G54D189*
X1445300Y419350D03*
X1439000Y427618D03*
Y419350D03*
X1445300Y427618D03*
X1863750Y168234D03*
X1870050Y159966D03*
Y168234D03*
X1863750Y159966D03*
X1905450Y133010D03*
X1911750Y124742D03*
Y133010D03*
X1905450Y124742D03*
G54D87*
X105712Y375972D03*
X1535557Y350894D03*
X1657144Y241740D03*
X1661766Y235420D03*
X1850498Y87606D03*
G54D297*
X1953740Y217834D03*
Y215866D03*
Y213897D03*
Y233582D03*
Y231614D03*
Y225708D03*
Y223740D03*
X1960433Y217834D03*
Y215866D03*
Y233582D03*
Y231614D03*
Y229645D03*
Y227677D03*
Y225708D03*
Y223740D03*
Y221771D03*
Y219803D03*
G54D69*
X67500Y255200D03*
X68053Y232300D03*
G54D198*
X1421647Y534305D03*
X1420072D03*
X1418497D03*
X1416922D03*
X1415347D03*
X1413773D03*
X1412198D03*
X1410623D03*
X1409048D03*
X1407473D03*
X1565287Y595850D03*
X1563712D03*
X1562137D03*
X1560562D03*
X1558987D03*
X1557413D03*
X1555838D03*
X1554263D03*
X1552688D03*
X1551113D03*
G54D96*
X270109Y216909D03*
X276869D03*
X283629D03*
X290389D03*
X266729Y214960D03*
X273489D03*
X280249D03*
X287009D03*
X270109Y213009D03*
X276869D03*
X283629D03*
X290389D03*
X266729Y211060D03*
X273489D03*
X280249D03*
X287009D03*
X270109Y209109D03*
X276869D03*
X283629D03*
X290389D03*
X273489Y207159D03*
X280249D03*
X287009D03*
X276869Y205210D03*
X283629D03*
X290389D03*
X273489Y203260D03*
X280249D03*
X287009D03*
X276869Y201309D03*
X283629D03*
X290389D03*
X280249Y199360D03*
X287009D03*
X283629Y197409D03*
X290389D03*
X270109Y232509D03*
X276869D03*
X283629D03*
X290389D03*
X266729Y230559D03*
X273489D03*
X280249D03*
X287009D03*
X270109Y228610D03*
X276869D03*
X283629D03*
X290389D03*
X266729Y226660D03*
X273489D03*
X280249D03*
X287009D03*
X270109Y224709D03*
X276869D03*
X283629D03*
X290389D03*
X270109Y220809D03*
X276869D03*
X283629D03*
X290389D03*
X266729Y218860D03*
X273489D03*
X280249D03*
X287009D03*
X270109Y279310D03*
X276869D03*
X283629D03*
X290389D03*
X273489Y277360D03*
X280249D03*
X287009D03*
X270109Y275409D03*
X276869D03*
X283629D03*
X290389D03*
X266729Y273460D03*
X273489D03*
X280249D03*
X287009D03*
X270109Y271509D03*
X276869D03*
X283629D03*
X290389D03*
X266729Y269560D03*
X273489D03*
X280249D03*
X287009D03*
X270109Y267609D03*
X276869D03*
X283629D03*
X290389D03*
X266729Y265660D03*
X273489D03*
X280249D03*
X287009D03*
X270109Y263709D03*
X276869D03*
X283629D03*
X290389D03*
X266729Y261760D03*
X273489D03*
X280249D03*
X287009D03*
X270109Y259809D03*
X276869D03*
X283629D03*
X290389D03*
X266729Y257860D03*
X273489D03*
X280249D03*
X287009D03*
X270109Y255909D03*
X276869D03*
X283629D03*
X290389D03*
X266729Y253960D03*
X273489D03*
X280249D03*
X287009D03*
X270109Y252009D03*
X276869D03*
X283629D03*
X290389D03*
X266729Y250060D03*
X273489D03*
X280249D03*
X287009D03*
X270109Y248109D03*
X276869D03*
X283629D03*
X290389D03*
X266729Y246160D03*
X273489D03*
X280249D03*
X287009D03*
X270109Y244209D03*
X276869D03*
X283629D03*
X290389D03*
X266729Y242260D03*
X273489D03*
X280249D03*
X287009D03*
X270109Y240309D03*
X276869D03*
X283629D03*
X290389D03*
X266729Y238360D03*
X273489D03*
X280249D03*
X287009D03*
X270109Y236409D03*
X276869D03*
X283629D03*
X290389D03*
X266729Y234460D03*
X273489D03*
X280249D03*
X287009D03*
X266729Y222760D03*
X273489D03*
X280249D03*
X287009D03*
X270109Y341709D03*
X276869D03*
X283629D03*
X290389D03*
X266729Y339760D03*
X273489D03*
X280249D03*
X287009D03*
X270109Y337809D03*
X276869D03*
X283629D03*
X290389D03*
X266729Y335860D03*
X273489D03*
X280249D03*
X287009D03*
X270109Y333909D03*
X276869D03*
X283629D03*
X290389D03*
X266729Y331960D03*
X273489D03*
X280249D03*
X287009D03*
X270109Y330009D03*
X276869D03*
X283629D03*
X290389D03*
X266729Y328060D03*
X273489D03*
X280249D03*
X287009D03*
X270109Y326110D03*
X276869D03*
X283629D03*
X290389D03*
X273489Y324160D03*
X280249D03*
X287009D03*
X270109Y322209D03*
X276869D03*
X283629D03*
X290389D03*
X273489Y320260D03*
X280249D03*
X287009D03*
X270109Y318309D03*
X276869D03*
X283629D03*
X290389D03*
X273489Y316360D03*
X280249D03*
X287009D03*
X276869Y314409D03*
X283629D03*
X290389D03*
X273489Y312460D03*
X280249D03*
X287009D03*
X276869Y310509D03*
X283629D03*
X290389D03*
X273489Y308560D03*
X280249D03*
X287009D03*
X276869Y306609D03*
X283629D03*
X290389D03*
X273489Y304660D03*
X280249D03*
X287009D03*
X276869Y302709D03*
X283629D03*
X290389D03*
X273489Y300760D03*
X280249D03*
X287009D03*
X276869Y298809D03*
X283629D03*
X290389D03*
X273489Y296860D03*
X280249D03*
X287009D03*
X276869Y294909D03*
X283629D03*
X290389D03*
X273489Y292959D03*
X280249D03*
X287009D03*
X276869Y291009D03*
X283629D03*
X290389D03*
X273489Y289060D03*
X280249D03*
X287009D03*
X276869Y287109D03*
X283629D03*
X290389D03*
X273489Y285160D03*
X280249D03*
X287009D03*
X270109Y283209D03*
X276869D03*
X283629D03*
X290389D03*
X273489Y281260D03*
X280249D03*
X287009D03*
X276869Y400209D03*
X283629D03*
X290389D03*
X273489Y398260D03*
X280249D03*
X287009D03*
X276869Y396309D03*
X283629D03*
X290389D03*
X273489Y394359D03*
X280249D03*
X287009D03*
X270109Y392410D03*
X276869D03*
X283629D03*
X290389D03*
X273489Y390460D03*
X280249D03*
X287009D03*
X270109Y388509D03*
X276869D03*
X283629D03*
X290389D03*
X273489Y386560D03*
X280249D03*
X287009D03*
X270109Y384609D03*
X276869D03*
X283629D03*
X290389D03*
X273489Y382660D03*
X280249D03*
X287009D03*
X270109Y380709D03*
X276869D03*
X283629D03*
X290389D03*
X273489Y378760D03*
X280249D03*
X287009D03*
X270109Y376809D03*
X276869D03*
X283629D03*
X290389D03*
X273489Y374860D03*
X280249D03*
X287009D03*
X273489Y370959D03*
X280249D03*
X287009D03*
X270109Y369010D03*
X276869D03*
X283629D03*
X290389D03*
X273489Y367060D03*
X280249D03*
X287009D03*
X270109Y365109D03*
X276869D03*
X283629D03*
X290389D03*
X273489Y363160D03*
X280249D03*
X287009D03*
X270109Y361209D03*
X276869D03*
X283629D03*
X290389D03*
X273489Y359260D03*
X280249D03*
X287009D03*
X270109Y357309D03*
X276869D03*
X283629D03*
X290389D03*
X266729Y355360D03*
X273489D03*
X280249D03*
X287009D03*
X270109Y353409D03*
X276869D03*
X283629D03*
X290389D03*
X266729Y351460D03*
X273489D03*
X280249D03*
X287009D03*
X270109Y349509D03*
X276869D03*
X283629D03*
X290389D03*
X266729Y347560D03*
X273489D03*
X280249D03*
X287009D03*
X270109Y345609D03*
X276869D03*
X283629D03*
X290389D03*
X266729Y343660D03*
X273489D03*
X280249D03*
X287009D03*
X270109Y372909D03*
X276869D03*
X283629D03*
X290389D03*
X297149Y216909D03*
X303909D03*
X310668D03*
X317428D03*
X324188D03*
X330948D03*
X337708D03*
X344468D03*
X351228D03*
X293769Y214960D03*
X300529D03*
X307289D03*
X314048D03*
X320808D03*
X327568D03*
X334328D03*
X341088D03*
X347848D03*
X354607D03*
X297149Y213009D03*
X303909D03*
X310668D03*
X317428D03*
X324188D03*
X330948D03*
X337708D03*
X344468D03*
X351228D03*
X293769Y211060D03*
X300529D03*
X307289D03*
X314048D03*
X320808D03*
X327568D03*
X334328D03*
X341088D03*
X347848D03*
X354607D03*
X297149Y209109D03*
X303909D03*
X310668D03*
X317428D03*
X324188D03*
X330948D03*
X337708D03*
X344468D03*
X351228D03*
X293769Y207159D03*
X300529D03*
X307289D03*
X314048D03*
X320808D03*
X327568D03*
X334328D03*
X341088D03*
X347848D03*
X354607D03*
X297149Y205210D03*
X303909D03*
X310668D03*
X317428D03*
X324188D03*
X330948D03*
X337708D03*
X344468D03*
X351228D03*
X293769Y203260D03*
X300529D03*
X307289D03*
X314048D03*
X334328D03*
X341088D03*
X347848D03*
X354607D03*
X297149Y201309D03*
X303909D03*
X310668D03*
X317428D03*
X337708D03*
X344468D03*
X351228D03*
X293769Y199360D03*
X300529D03*
X307289D03*
X314048D03*
X341088D03*
X347848D03*
X354607D03*
X297149Y197409D03*
X303909D03*
X310668D03*
X317428D03*
X344468D03*
X351228D03*
X297149Y232509D03*
X303909D03*
X310668D03*
X317428D03*
X324188D03*
X330948D03*
X337708D03*
X344468D03*
X351228D03*
X293769Y230559D03*
X300529D03*
X307289D03*
X314048D03*
X320808D03*
X327568D03*
X334328D03*
X341088D03*
X347848D03*
X354607D03*
X297149Y228610D03*
X303909D03*
X310668D03*
X317428D03*
X324188D03*
X330948D03*
X337708D03*
X344468D03*
X351228D03*
X293769Y226660D03*
X300529D03*
X307289D03*
X314048D03*
X320808D03*
X327568D03*
X334328D03*
X341088D03*
X347848D03*
X354607D03*
X297149Y224709D03*
X303909D03*
X310668D03*
X317428D03*
X324188D03*
X330948D03*
X337708D03*
X344468D03*
X351228D03*
X297149Y220809D03*
X303909D03*
X310668D03*
X317428D03*
X324188D03*
X330948D03*
X337708D03*
X344468D03*
X351228D03*
X293769Y218860D03*
X300529D03*
X307289D03*
X314048D03*
X320808D03*
X327568D03*
X334328D03*
X341088D03*
X347848D03*
X354607D03*
X297149Y279310D03*
X303909D03*
X310668D03*
X317428D03*
X324188D03*
X330948D03*
X337708D03*
X344468D03*
X351228D03*
X293769Y277360D03*
X300529D03*
X307289D03*
X314048D03*
X320808D03*
X327568D03*
X334328D03*
X341088D03*
X347848D03*
X354607D03*
X297149Y275409D03*
X303909D03*
X310668D03*
X317428D03*
X324188D03*
X330948D03*
X337708D03*
X344468D03*
X351228D03*
X293769Y273460D03*
X300529D03*
X307289D03*
X314048D03*
X320808D03*
X327568D03*
X334328D03*
X341088D03*
X347848D03*
X354607D03*
X297149Y271509D03*
X303909D03*
X310668D03*
X317428D03*
X324188D03*
X330948D03*
X337708D03*
X344468D03*
X351228D03*
X293769Y269560D03*
X300529D03*
X307289D03*
X314048D03*
X320808D03*
X327568D03*
X334328D03*
X341088D03*
X347848D03*
X354607D03*
X297149Y267609D03*
X303909D03*
X310668D03*
X317428D03*
X324188D03*
X330948D03*
X337708D03*
X344468D03*
X351228D03*
X293769Y265660D03*
X300529D03*
X307289D03*
X314048D03*
X320808D03*
X327568D03*
X334328D03*
X341088D03*
X347848D03*
X354607D03*
X297149Y263709D03*
X303909D03*
X310668D03*
X317428D03*
X324188D03*
X330948D03*
X337708D03*
X344468D03*
X351228D03*
X293769Y261760D03*
X300529D03*
X307289D03*
X314048D03*
X327568D03*
X334328D03*
X341088D03*
X347848D03*
X354607D03*
X297149Y259809D03*
X303909D03*
X310668D03*
X324188D03*
X330948D03*
X337708D03*
X344468D03*
X351228D03*
X293769Y257860D03*
X300529D03*
X307289D03*
X327568D03*
X334328D03*
X341088D03*
X347848D03*
X354607D03*
X297149Y255909D03*
X303909D03*
X310668D03*
X324188D03*
X330948D03*
X337708D03*
X344468D03*
X351228D03*
X293769Y253960D03*
X300529D03*
X307289D03*
X327568D03*
X334328D03*
X341088D03*
X347848D03*
X354607D03*
X297149Y252009D03*
X303909D03*
X310668D03*
X324188D03*
X330948D03*
X337708D03*
X344468D03*
X351228D03*
X293769Y250060D03*
X300529D03*
X307289D03*
X320808D03*
X327568D03*
X334328D03*
X341088D03*
X347848D03*
X354607D03*
X297149Y248109D03*
X303909D03*
X310668D03*
X317428D03*
X324188D03*
X330948D03*
X337708D03*
X344468D03*
X351228D03*
X293769Y246160D03*
X300529D03*
X307289D03*
X314048D03*
X320808D03*
X327568D03*
X334328D03*
X341088D03*
X347848D03*
X354607D03*
X297149Y244209D03*
X303909D03*
X310668D03*
X317428D03*
X324188D03*
X330948D03*
X337708D03*
X344468D03*
X351228D03*
X293769Y242260D03*
X300529D03*
X307289D03*
X314048D03*
X320808D03*
X327568D03*
X334328D03*
X341088D03*
X347848D03*
X354607D03*
X297149Y240309D03*
X303909D03*
X310668D03*
X317428D03*
X324188D03*
X330948D03*
X337708D03*
X344468D03*
X351228D03*
X293769Y238360D03*
X300529D03*
X307289D03*
X314048D03*
X320808D03*
X327568D03*
X334328D03*
X341088D03*
X347848D03*
X354607D03*
X297149Y236409D03*
X303909D03*
X310668D03*
X317428D03*
X324188D03*
X330948D03*
X337708D03*
X344468D03*
X351228D03*
X293769Y234460D03*
X300529D03*
X307289D03*
X314048D03*
X320808D03*
X327568D03*
X334328D03*
X341088D03*
X347848D03*
X354607D03*
X293769Y222760D03*
X300529D03*
X307289D03*
X314048D03*
X320808D03*
X327568D03*
X334328D03*
X341088D03*
X347848D03*
X354607D03*
X297149Y341709D03*
X303909D03*
X310668D03*
X324188D03*
X330948D03*
X337708D03*
X344468D03*
X351228D03*
X293769Y339760D03*
X300529D03*
X307289D03*
X327568D03*
X334328D03*
X341088D03*
X347848D03*
X354607D03*
X297149Y337809D03*
X303909D03*
X310668D03*
X324188D03*
X330948D03*
X337708D03*
X344468D03*
X351228D03*
X293769Y335860D03*
X300529D03*
X307289D03*
X320808D03*
X327568D03*
X334328D03*
X341088D03*
X347848D03*
X354607D03*
X297149Y333909D03*
X303909D03*
X310668D03*
X317428D03*
X324188D03*
X330948D03*
X337708D03*
X344468D03*
X351228D03*
X293769Y331960D03*
X300529D03*
X307289D03*
X314048D03*
X320808D03*
X327568D03*
X334328D03*
X341088D03*
X347848D03*
X354607D03*
X297149Y330009D03*
X303909D03*
X310668D03*
X317428D03*
X324188D03*
X330948D03*
X337708D03*
X344468D03*
X351228D03*
X293769Y328060D03*
X300529D03*
X307289D03*
X314048D03*
X320808D03*
X327568D03*
X334328D03*
X341088D03*
X347848D03*
X354607D03*
X297149Y326110D03*
X303909D03*
X310668D03*
X317428D03*
X324188D03*
X330948D03*
X337708D03*
X344468D03*
X351228D03*
X293769Y324160D03*
X300529D03*
X307289D03*
X314048D03*
X320808D03*
X327568D03*
X334328D03*
X341088D03*
X347848D03*
X354607D03*
X297149Y322209D03*
X303909D03*
X310668D03*
X317428D03*
X324188D03*
X330948D03*
X337708D03*
X344468D03*
X351228D03*
X293769Y320260D03*
X300529D03*
X307289D03*
X314048D03*
X320808D03*
X327568D03*
X334328D03*
X341088D03*
X347848D03*
X354607D03*
X297149Y318309D03*
X303909D03*
X310668D03*
X317428D03*
X324188D03*
X330948D03*
X337708D03*
X344468D03*
X351228D03*
X293769Y316360D03*
X300529D03*
X307289D03*
X314048D03*
X320808D03*
X327568D03*
X334328D03*
X341088D03*
X347848D03*
X354607D03*
X297149Y314409D03*
X303909D03*
X310668D03*
X317428D03*
X324188D03*
X330948D03*
X337708D03*
X344468D03*
X351228D03*
X293769Y312460D03*
X300529D03*
X307289D03*
X314048D03*
X320808D03*
X327568D03*
X334328D03*
X341088D03*
X347848D03*
X354607D03*
X297149Y310509D03*
X303909D03*
X310668D03*
X317428D03*
X324188D03*
X330948D03*
X337708D03*
X344468D03*
X351228D03*
X293769Y308560D03*
X300529D03*
X307289D03*
X314048D03*
X320808D03*
X327568D03*
X334328D03*
X341088D03*
X347848D03*
X354607D03*
X297149Y306609D03*
X303909D03*
X310668D03*
X317428D03*
X324188D03*
X330948D03*
X337708D03*
X344468D03*
X351228D03*
X293769Y304660D03*
X300529D03*
X307289D03*
X314048D03*
X320808D03*
X327568D03*
X334328D03*
X341088D03*
X347848D03*
X354607D03*
X297149Y302709D03*
X303909D03*
X310668D03*
X317428D03*
X324188D03*
X330948D03*
X337708D03*
X344468D03*
X351228D03*
X293769Y300760D03*
X300529D03*
X307289D03*
X314048D03*
X320808D03*
X327568D03*
X334328D03*
X341088D03*
X347848D03*
X354607D03*
X297149Y298809D03*
X303909D03*
X310668D03*
X317428D03*
X324188D03*
X330948D03*
X337708D03*
X344468D03*
X351228D03*
X293769Y296860D03*
X300529D03*
X307289D03*
X314048D03*
X320808D03*
X327568D03*
X334328D03*
X341088D03*
X347848D03*
X354607D03*
X297149Y294909D03*
X303909D03*
X310668D03*
X317428D03*
X324188D03*
X330948D03*
X337708D03*
X344468D03*
X351228D03*
X293769Y292959D03*
X300529D03*
X307289D03*
X314048D03*
X320808D03*
X327568D03*
X334328D03*
X341088D03*
X347848D03*
X354607D03*
X297149Y291009D03*
X303909D03*
X310668D03*
X317428D03*
X324188D03*
X330948D03*
X337708D03*
X344468D03*
X351228D03*
X293769Y289060D03*
X300529D03*
X307289D03*
X314048D03*
X320808D03*
X327568D03*
X334328D03*
X341088D03*
X347848D03*
X354607D03*
X297149Y287109D03*
X303909D03*
X310668D03*
X317428D03*
X324188D03*
X330948D03*
X337708D03*
X344468D03*
X351228D03*
X293769Y285160D03*
X300529D03*
X307289D03*
X314048D03*
X320808D03*
X327568D03*
X334328D03*
X341088D03*
X347848D03*
X354607D03*
X297149Y283209D03*
X303909D03*
X310668D03*
X317428D03*
X324188D03*
X330948D03*
X337708D03*
X344468D03*
X351228D03*
X293769Y281260D03*
X300529D03*
X307289D03*
X314048D03*
X320808D03*
X327568D03*
X334328D03*
X341088D03*
X347848D03*
X354607D03*
X297149Y400209D03*
X303909D03*
X310668D03*
X317428D03*
X344468D03*
X351228D03*
X293769Y398260D03*
X300529D03*
X307289D03*
X314048D03*
X320808D03*
X347848D03*
X354607D03*
X297149Y396309D03*
X303909D03*
X310668D03*
X317428D03*
X324188D03*
X344468D03*
X351228D03*
X293769Y394359D03*
X300529D03*
X307289D03*
X314048D03*
X320808D03*
X347848D03*
X354607D03*
X297149Y392410D03*
X303909D03*
X310668D03*
X317428D03*
X324188D03*
X330948D03*
X337708D03*
X344468D03*
X351228D03*
X293769Y390460D03*
X300529D03*
X307289D03*
X314048D03*
X320808D03*
X327568D03*
X334328D03*
X341088D03*
X347848D03*
X354607D03*
X297149Y388509D03*
X303909D03*
X310668D03*
X317428D03*
X324188D03*
X330948D03*
X337708D03*
X344468D03*
X351228D03*
X293769Y386560D03*
X300529D03*
X307289D03*
X314048D03*
X320808D03*
X327568D03*
X334328D03*
X341088D03*
X347848D03*
X354607D03*
X297149Y384609D03*
X303909D03*
X310668D03*
X317428D03*
X324188D03*
X330948D03*
X337708D03*
X344468D03*
X351228D03*
X293769Y382660D03*
X300529D03*
X307289D03*
X314048D03*
X320808D03*
X327568D03*
X334328D03*
X341088D03*
X347848D03*
X354607D03*
X297149Y380709D03*
X303909D03*
X310668D03*
X317428D03*
X324188D03*
X330948D03*
X337708D03*
X344468D03*
X351228D03*
X293769Y378760D03*
X300529D03*
X307289D03*
X314048D03*
X320808D03*
X327568D03*
X334328D03*
X341088D03*
X347848D03*
X354607D03*
X297149Y376809D03*
X303909D03*
X310668D03*
X317428D03*
X324188D03*
X330948D03*
X337708D03*
X344468D03*
X351228D03*
X293769Y374860D03*
X300529D03*
X307289D03*
X314048D03*
X320808D03*
X327568D03*
X334328D03*
X341088D03*
X347848D03*
X354607D03*
X293769Y370959D03*
X300529D03*
X307289D03*
X314048D03*
X320808D03*
X327568D03*
X334328D03*
X341088D03*
X347848D03*
X354607D03*
X297149Y369010D03*
X303909D03*
X310668D03*
X317428D03*
X324188D03*
X330948D03*
X337708D03*
X344468D03*
X351228D03*
X293769Y367060D03*
X300529D03*
X307289D03*
X314048D03*
X320808D03*
X327568D03*
X334328D03*
X341088D03*
X347848D03*
X354607D03*
X297149Y365109D03*
X303909D03*
X310668D03*
X317428D03*
X324188D03*
X330948D03*
X337708D03*
X344468D03*
X351228D03*
X293769Y363160D03*
X300529D03*
X307289D03*
X314048D03*
X320808D03*
X327568D03*
X334328D03*
X341088D03*
X347848D03*
X354607D03*
X297149Y361209D03*
X303909D03*
X310668D03*
X317428D03*
X324188D03*
X330948D03*
X337708D03*
X344468D03*
X351228D03*
X293769Y359260D03*
X300529D03*
X307289D03*
X314048D03*
X320808D03*
X327568D03*
X334328D03*
X341088D03*
X347848D03*
X354607D03*
X297149Y357309D03*
X303909D03*
X310668D03*
X317428D03*
X324188D03*
X330948D03*
X337708D03*
X344468D03*
X351228D03*
X293769Y355360D03*
X300529D03*
X307289D03*
X314048D03*
X320808D03*
X327568D03*
X334328D03*
X341088D03*
X347848D03*
X354607D03*
X297149Y353409D03*
X303909D03*
X310668D03*
X317428D03*
X324188D03*
X330948D03*
X337708D03*
X344468D03*
X351228D03*
X293769Y351460D03*
X300529D03*
X307289D03*
X314048D03*
X320808D03*
X327568D03*
X334328D03*
X341088D03*
X347848D03*
X354607D03*
X297149Y349509D03*
X303909D03*
X310668D03*
X317428D03*
X324188D03*
X330948D03*
X337708D03*
X344468D03*
X351228D03*
X293769Y347560D03*
X300529D03*
X307289D03*
X314048D03*
X327568D03*
X334328D03*
X341088D03*
X347848D03*
X354607D03*
X297149Y345609D03*
X303909D03*
X310668D03*
X324188D03*
X330948D03*
X337708D03*
X344468D03*
X351228D03*
X293769Y343660D03*
X300529D03*
X307289D03*
X327568D03*
X334328D03*
X341088D03*
X347848D03*
X354607D03*
X297149Y372909D03*
X303909D03*
X310668D03*
X317428D03*
X324188D03*
X330948D03*
X337708D03*
X344468D03*
X351228D03*
X357987Y216909D03*
X364747D03*
X371507D03*
X378267D03*
X385027D03*
X391787D03*
X398546D03*
X405306D03*
X361367Y214960D03*
X368127D03*
X374887D03*
X381647D03*
X388407D03*
X395166D03*
X401926D03*
X357987Y213009D03*
X364747D03*
X371507D03*
X378267D03*
X385027D03*
X391787D03*
X398546D03*
X405306D03*
X361367Y211060D03*
X368127D03*
X374887D03*
X381647D03*
X388407D03*
X395166D03*
X401926D03*
X357987Y209109D03*
X364747D03*
X371507D03*
X378267D03*
X385027D03*
X391787D03*
X398546D03*
X405306D03*
X361367Y207159D03*
X368127D03*
X374887D03*
X381647D03*
X388407D03*
X395166D03*
X401926D03*
X357987Y205210D03*
X364747D03*
X371507D03*
X378267D03*
X385027D03*
X391787D03*
X398546D03*
X405306D03*
X361367Y203260D03*
X368127D03*
X374887D03*
X381647D03*
X388407D03*
X395166D03*
X401926D03*
X357987Y201309D03*
X364747D03*
X371507D03*
X378267D03*
X385027D03*
X391787D03*
X398546D03*
X405306D03*
X361367Y199360D03*
X368127D03*
X374887D03*
X381647D03*
X388407D03*
X395166D03*
X401926D03*
X357987Y197409D03*
X364747D03*
X371507D03*
X378267D03*
X385027D03*
X391787D03*
X398546D03*
X357987Y232509D03*
X364747D03*
X371507D03*
X378267D03*
X385027D03*
X391787D03*
X398546D03*
X405306D03*
X361367Y230559D03*
X368127D03*
X374887D03*
X381647D03*
X388407D03*
X395166D03*
X401926D03*
X357987Y228610D03*
X364747D03*
X371507D03*
X378267D03*
X385027D03*
X391787D03*
X398546D03*
X405306D03*
X361367Y226660D03*
X368127D03*
X374887D03*
X381647D03*
X388407D03*
X395166D03*
X401926D03*
X357987Y224709D03*
X364747D03*
X371507D03*
X378267D03*
X385027D03*
X391787D03*
X398546D03*
X405306D03*
X357987Y220809D03*
X364747D03*
X371507D03*
X378267D03*
X385027D03*
X391787D03*
X398546D03*
X405306D03*
X361367Y218860D03*
X368127D03*
X374887D03*
X381647D03*
X388407D03*
X395166D03*
X401926D03*
X357987Y267609D03*
X361367Y265660D03*
X357987Y263709D03*
X364747D03*
X361367Y261760D03*
X368127D03*
X357987Y259809D03*
X364747D03*
X371507D03*
X361367Y257860D03*
X368127D03*
X374887D03*
X357987Y255909D03*
X364747D03*
X371507D03*
X378267D03*
X361367Y253960D03*
X368127D03*
X374887D03*
X381647D03*
X388407D03*
X395166D03*
X401926D03*
X357987Y252009D03*
X364747D03*
X371507D03*
X378267D03*
X385027D03*
X391787D03*
X398546D03*
X405306D03*
X361367Y250060D03*
X368127D03*
X374887D03*
X381647D03*
X388407D03*
X395166D03*
X401926D03*
X357987Y248109D03*
X364747D03*
X371507D03*
X378267D03*
X385027D03*
X391787D03*
X398546D03*
X405306D03*
X361367Y246160D03*
X368127D03*
X374887D03*
X381647D03*
X388407D03*
X395166D03*
X401926D03*
X357987Y244209D03*
X364747D03*
X371507D03*
X378267D03*
X385027D03*
X391787D03*
X398546D03*
X405306D03*
X361367Y242260D03*
X368127D03*
X374887D03*
X381647D03*
X388407D03*
X395166D03*
X401926D03*
X357987Y240309D03*
X364747D03*
X371507D03*
X378267D03*
X385027D03*
X391787D03*
X398546D03*
X405306D03*
X361367Y238360D03*
X368127D03*
X374887D03*
X381647D03*
X388407D03*
X395166D03*
X401926D03*
X357987Y236409D03*
X364747D03*
X371507D03*
X378267D03*
X385027D03*
X391787D03*
X398546D03*
X405306D03*
X361367Y234460D03*
X368127D03*
X374887D03*
X381647D03*
X388407D03*
X395166D03*
X401926D03*
X361367Y222760D03*
X368127D03*
X374887D03*
X381647D03*
X388407D03*
X395166D03*
X401926D03*
X357987Y341709D03*
X364747D03*
X371507D03*
X378267D03*
X361367Y339760D03*
X368127D03*
X374887D03*
X357987Y337809D03*
X364747D03*
X371507D03*
X361367Y335860D03*
X368127D03*
X357987Y333909D03*
X364747D03*
X361367Y331960D03*
X357987Y330009D03*
Y400209D03*
X364747D03*
X371507D03*
X378267D03*
X385027D03*
X391787D03*
X398546D03*
X405306D03*
X361367Y398260D03*
X368127D03*
X374887D03*
X381647D03*
X388407D03*
X395166D03*
X401926D03*
X408686D03*
X357987Y396309D03*
X364747D03*
X371507D03*
X378267D03*
X385027D03*
X391787D03*
X398546D03*
X405306D03*
X361367Y394359D03*
X368127D03*
X374887D03*
X381647D03*
X388407D03*
X395166D03*
X401926D03*
X408686D03*
X357987Y392410D03*
X364747D03*
X371507D03*
X378267D03*
X385027D03*
X391787D03*
X398546D03*
X405306D03*
X361367Y390460D03*
X368127D03*
X374887D03*
X381647D03*
X388407D03*
X395166D03*
X401926D03*
X408686D03*
X357987Y388509D03*
X364747D03*
X371507D03*
X378267D03*
X385027D03*
X391787D03*
X398546D03*
X405306D03*
X361367Y386560D03*
X368127D03*
X374887D03*
X381647D03*
X388407D03*
X395166D03*
X401926D03*
X408686D03*
X357987Y384609D03*
X364747D03*
X371507D03*
X378267D03*
X385027D03*
X391787D03*
X398546D03*
X405306D03*
X361367Y382660D03*
X368127D03*
X374887D03*
X381647D03*
X388407D03*
X395166D03*
X401926D03*
X408686D03*
X357987Y380709D03*
X364747D03*
X371507D03*
X378267D03*
X385027D03*
X391787D03*
X398546D03*
X405306D03*
X361367Y378760D03*
X368127D03*
X374887D03*
X381647D03*
X388407D03*
X395166D03*
X401926D03*
X408686D03*
X357987Y376809D03*
X364747D03*
X371507D03*
X378267D03*
X385027D03*
X391787D03*
X398546D03*
X405306D03*
X361367Y374860D03*
X368127D03*
X374887D03*
X381647D03*
X388407D03*
X395166D03*
X401926D03*
X408686D03*
X361367Y370959D03*
X368127D03*
X374887D03*
X381647D03*
X388407D03*
X395166D03*
X401926D03*
X408686D03*
X357987Y369010D03*
X364747D03*
X371507D03*
X378267D03*
X385027D03*
X391787D03*
X398546D03*
X405306D03*
X361367Y367060D03*
X368127D03*
X374887D03*
X381647D03*
X388407D03*
X395166D03*
X401926D03*
X408686D03*
X357987Y365109D03*
X364747D03*
X371507D03*
X378267D03*
X385027D03*
X391787D03*
X398546D03*
X405306D03*
X361367Y363160D03*
X368127D03*
X374887D03*
X381647D03*
X388407D03*
X395166D03*
X401926D03*
X408686D03*
X357987Y361209D03*
X364747D03*
X371507D03*
X378267D03*
X385027D03*
X391787D03*
X398546D03*
X405306D03*
X361367Y359260D03*
X368127D03*
X374887D03*
X381647D03*
X388407D03*
X395166D03*
X401926D03*
X408686D03*
X357987Y357309D03*
X364747D03*
X371507D03*
X378267D03*
X385027D03*
X391787D03*
X398546D03*
X405306D03*
X361367Y355360D03*
X368127D03*
X374887D03*
X381647D03*
X388407D03*
X395166D03*
X401926D03*
X408686D03*
X357987Y353409D03*
X364747D03*
X371507D03*
X378267D03*
X385027D03*
X391787D03*
X398546D03*
X405306D03*
X361367Y351460D03*
X368127D03*
X374887D03*
X381647D03*
X388407D03*
X395166D03*
X401926D03*
X408686D03*
X357987Y349509D03*
X364747D03*
X371507D03*
X378267D03*
X385027D03*
X391787D03*
X398546D03*
X405306D03*
X361367Y347560D03*
X368127D03*
X374887D03*
X381647D03*
X388407D03*
X395166D03*
X401926D03*
X357987Y345609D03*
X364747D03*
X371507D03*
X378267D03*
X385027D03*
X361367Y343660D03*
X368127D03*
X374887D03*
X381647D03*
X357987Y372909D03*
X364747D03*
X371507D03*
X378267D03*
X385027D03*
X391787D03*
X398546D03*
X405306D03*
X421464Y218147D03*
X428224D03*
X434983D03*
X441743D03*
X448503D03*
X455263D03*
X462023D03*
X468783D03*
X475542D03*
X418084Y216196D03*
X424844D03*
X431604D03*
X438363D03*
X445123D03*
X451883D03*
X458643D03*
X465403D03*
X472163D03*
X421464Y214247D03*
X428224D03*
X434983D03*
X441743D03*
X448503D03*
X455263D03*
X462023D03*
X468783D03*
X475542D03*
X418084Y212296D03*
X424844D03*
X431604D03*
X438363D03*
X445123D03*
X451883D03*
X458643D03*
X465403D03*
X472163D03*
X421464Y210346D03*
X428224D03*
X434983D03*
X441743D03*
X448503D03*
X455263D03*
X462023D03*
X468783D03*
X475542D03*
X418084Y208397D03*
X424844D03*
X431604D03*
X438363D03*
X445123D03*
X451883D03*
X458643D03*
X465403D03*
X472163D03*
X421464Y206447D03*
X428224D03*
X434983D03*
X441743D03*
X448503D03*
X455263D03*
X462023D03*
X468783D03*
X475542D03*
X418084Y204496D03*
X424844D03*
X431604D03*
X438363D03*
X445123D03*
X451883D03*
X458643D03*
X465403D03*
X472163D03*
X421464Y202547D03*
X428224D03*
X434983D03*
X441743D03*
X448503D03*
X455263D03*
X462023D03*
X468783D03*
X475542D03*
X418084Y239596D03*
X424844D03*
X431604D03*
X438363D03*
X445123D03*
X451883D03*
X458643D03*
X465403D03*
X472163D03*
X421464Y237647D03*
X428224D03*
X434983D03*
X441743D03*
X448503D03*
X455263D03*
X462023D03*
X468783D03*
X475542D03*
X418084Y235696D03*
X424844D03*
X431604D03*
X438363D03*
X445123D03*
X451883D03*
X458643D03*
X465403D03*
X472163D03*
X421464Y233746D03*
X428224D03*
X434983D03*
X441743D03*
X448503D03*
X455263D03*
X462023D03*
X468783D03*
X475542D03*
X418084Y231797D03*
X424844D03*
X431604D03*
X438363D03*
X445123D03*
X451883D03*
X458643D03*
X465403D03*
X472163D03*
X418084Y227896D03*
X424844D03*
X431604D03*
X438363D03*
X445123D03*
X451883D03*
X458643D03*
X465403D03*
X472163D03*
X421464Y225947D03*
X428224D03*
X434983D03*
X441743D03*
X448503D03*
X455263D03*
X462023D03*
X468783D03*
X475542D03*
X418084Y223996D03*
X424844D03*
X431604D03*
X438363D03*
X445123D03*
X451883D03*
X458643D03*
X465403D03*
X472163D03*
X421464Y222047D03*
X428224D03*
X434983D03*
X441743D03*
X448503D03*
X455263D03*
X462023D03*
X468783D03*
X475542D03*
X418084Y220096D03*
X424844D03*
X431604D03*
X438363D03*
X445123D03*
X451883D03*
X458643D03*
X465403D03*
X472163D03*
Y278596D03*
X475542Y276646D03*
X472163Y274696D03*
X468783Y272747D03*
X475542D03*
X465403Y270796D03*
X472163D03*
X462023Y268847D03*
X468783D03*
X475542D03*
X458643Y266896D03*
X465403D03*
X472163D03*
X455263Y264947D03*
X462023D03*
X468783D03*
X475542D03*
X451883Y262996D03*
X458643D03*
X465403D03*
X472163D03*
X448503Y261047D03*
X455263D03*
X462023D03*
X468783D03*
X475542D03*
X445123Y259096D03*
X451883D03*
X458643D03*
X465403D03*
X472163D03*
X441743Y257147D03*
X448503D03*
X455263D03*
X462023D03*
X468783D03*
X475542D03*
X424844Y255196D03*
X431604D03*
X438363D03*
X445123D03*
X451883D03*
X458643D03*
X465403D03*
X472163D03*
X421464Y253247D03*
X428224D03*
X434983D03*
X441743D03*
X448503D03*
X455263D03*
X462023D03*
X468783D03*
X475542D03*
X418084Y251296D03*
X424844D03*
X431604D03*
X438363D03*
X445123D03*
X451883D03*
X458643D03*
X465403D03*
X472163D03*
X421464Y249347D03*
X428224D03*
X434983D03*
X441743D03*
X448503D03*
X455263D03*
X462023D03*
X468783D03*
X475542D03*
X418084Y247396D03*
X424844D03*
X431604D03*
X438363D03*
X445123D03*
X451883D03*
X458643D03*
X465403D03*
X472163D03*
X421464Y245447D03*
X428224D03*
X434983D03*
X441743D03*
X448503D03*
X455263D03*
X462023D03*
X468783D03*
X475542D03*
X418084Y243496D03*
X424844D03*
X431604D03*
X438363D03*
X445123D03*
X451883D03*
X458643D03*
X465403D03*
X472163D03*
X421464Y241547D03*
X428224D03*
X434983D03*
X441743D03*
X448503D03*
X455263D03*
X462023D03*
X468783D03*
X475542D03*
X421464Y229847D03*
X428224D03*
X434983D03*
X441743D03*
X448503D03*
X455263D03*
X462023D03*
X468783D03*
X475542D03*
X458643Y340996D03*
X465403D03*
X472163D03*
X462023Y339047D03*
X468783D03*
X475542D03*
X465403Y337096D03*
X472163D03*
X468783Y335147D03*
X475542D03*
X472163Y333196D03*
X475542Y331247D03*
X472163Y329296D03*
X475542Y327347D03*
X472163Y325396D03*
X475542Y323446D03*
X472163Y321496D03*
X475542Y319547D03*
X472163Y317596D03*
X475542Y315647D03*
X472163Y313696D03*
X475542Y311747D03*
X472163Y309797D03*
X475542Y307847D03*
X472163Y305896D03*
X475542Y303947D03*
X472163Y301996D03*
X475542Y300047D03*
X472163Y298096D03*
X475542Y296147D03*
X472163Y294196D03*
X475542Y292247D03*
X472163Y290296D03*
X475542Y288347D03*
X472163Y286396D03*
X475542Y284447D03*
X472163Y282496D03*
X475542Y280547D03*
X424844Y403396D03*
X431604D03*
X438363D03*
X445123D03*
X451883D03*
X458643D03*
X465403D03*
X472163D03*
X421464Y401447D03*
X428224D03*
X434983D03*
X441743D03*
X448503D03*
X455263D03*
X462023D03*
X468783D03*
X475542D03*
X424844Y399496D03*
X431604D03*
X438363D03*
X445123D03*
X451883D03*
X458643D03*
X465403D03*
X472163D03*
X421464Y397546D03*
X428224D03*
X434983D03*
X441743D03*
X448503D03*
X455263D03*
X462023D03*
X468783D03*
X475542D03*
X424844Y395597D03*
X431604D03*
X438363D03*
X445123D03*
X451883D03*
X458643D03*
X465403D03*
X472163D03*
X421464Y393647D03*
X428224D03*
X434983D03*
X441743D03*
X448503D03*
X455263D03*
X462023D03*
X468783D03*
X475542D03*
X424844Y391696D03*
X431604D03*
X438363D03*
X445123D03*
X451883D03*
X458643D03*
X465403D03*
X472163D03*
X421464Y389747D03*
X428224D03*
X434983D03*
X441743D03*
X448503D03*
X455263D03*
X462023D03*
X468783D03*
X475542D03*
X424844Y387796D03*
X431604D03*
X438363D03*
X445123D03*
X451883D03*
X458643D03*
X465403D03*
X472163D03*
X421464Y385847D03*
X428224D03*
X434983D03*
X441743D03*
X448503D03*
X455263D03*
X462023D03*
X468783D03*
X475542D03*
X424844Y383896D03*
X431604D03*
X438363D03*
X445123D03*
X451883D03*
X458643D03*
X465403D03*
X472163D03*
X421464Y381947D03*
X428224D03*
X434983D03*
X441743D03*
X448503D03*
X455263D03*
X462023D03*
X468783D03*
X475542D03*
X421464Y378047D03*
X428224D03*
X434983D03*
X441743D03*
X448503D03*
X455263D03*
X462023D03*
X468783D03*
X475542D03*
X424844Y376096D03*
X431604D03*
X438363D03*
X445123D03*
X451883D03*
X458643D03*
X465403D03*
X472163D03*
X421464Y374146D03*
X428224D03*
X434983D03*
X441743D03*
X448503D03*
X455263D03*
X462023D03*
X468783D03*
X475542D03*
X424844Y372197D03*
X431604D03*
X438363D03*
X445123D03*
X451883D03*
X458643D03*
X465403D03*
X472163D03*
X421464Y370247D03*
X428224D03*
X434983D03*
X441743D03*
X448503D03*
X455263D03*
X462023D03*
X468783D03*
X475542D03*
X424844Y368296D03*
X431604D03*
X438363D03*
X445123D03*
X451883D03*
X458643D03*
X465403D03*
X472163D03*
X421464Y366347D03*
X428224D03*
X434983D03*
X441743D03*
X448503D03*
X455263D03*
X462023D03*
X468783D03*
X475542D03*
X424844Y364396D03*
X431604D03*
X438363D03*
X445123D03*
X451883D03*
X458643D03*
X465403D03*
X472163D03*
X421464Y362447D03*
X428224D03*
X434983D03*
X441743D03*
X448503D03*
X455263D03*
X462023D03*
X468783D03*
X475542D03*
X424844Y360496D03*
X431604D03*
X438363D03*
X445123D03*
X451883D03*
X458643D03*
X465403D03*
X472163D03*
X421464Y358547D03*
X428224D03*
X434983D03*
X441743D03*
X448503D03*
X455263D03*
X462023D03*
X468783D03*
X475542D03*
X424844Y356596D03*
X431604D03*
X438363D03*
X445123D03*
X451883D03*
X458643D03*
X465403D03*
X472163D03*
X421464Y354647D03*
X428224D03*
X434983D03*
X441743D03*
X448503D03*
X455263D03*
X462023D03*
X468783D03*
X475542D03*
X424844Y352696D03*
X431604D03*
X438363D03*
X445123D03*
X451883D03*
X458643D03*
X465403D03*
X472163D03*
X421464Y350747D03*
X428224D03*
X434983D03*
X441743D03*
X448503D03*
X455263D03*
X462023D03*
X468783D03*
X475542D03*
X424844Y348796D03*
X431604D03*
X438363D03*
X445123D03*
X451883D03*
X458643D03*
X465403D03*
X472163D03*
X448503Y346847D03*
X455263D03*
X462023D03*
X468783D03*
X475542D03*
X451883Y344896D03*
X458643D03*
X465403D03*
X472163D03*
X455263Y342947D03*
X462023D03*
X468783D03*
X475542D03*
X424844Y379996D03*
X431604D03*
X438363D03*
X445123D03*
X451883D03*
X458643D03*
X465403D03*
X472163D03*
X428224Y405347D03*
X434983D03*
X441743D03*
X448503D03*
X455263D03*
X462023D03*
X468783D03*
X475542D03*
X536381Y218147D03*
X482302D03*
X489062D03*
X495822D03*
X502582D03*
X509342D03*
X516102D03*
X522861D03*
X529621D03*
X533001Y216196D03*
X539761D03*
X478922D03*
X485682D03*
X492442D03*
X499202D03*
X505962D03*
X512722D03*
X519481D03*
X526241D03*
X536381Y214247D03*
X482302D03*
X489062D03*
X495822D03*
X502582D03*
X509342D03*
X516102D03*
X522861D03*
X529621D03*
X533001Y212296D03*
X539761D03*
X478922D03*
X485682D03*
X492442D03*
X499202D03*
X505962D03*
X512722D03*
X519481D03*
X526241D03*
X536381Y210346D03*
X482302D03*
X489062D03*
X495822D03*
X502582D03*
X509342D03*
X516102D03*
X522861D03*
X529621D03*
X533001Y208397D03*
X539761D03*
X478922D03*
X505962D03*
X512722D03*
X519481D03*
X526241D03*
X536381Y206447D03*
X482302D03*
X502582D03*
X509342D03*
X516102D03*
X522861D03*
X529621D03*
X533001Y204496D03*
X539761D03*
X478922D03*
X505962D03*
X512722D03*
X519481D03*
X526241D03*
X536381Y202547D03*
X482302D03*
X509342D03*
X516102D03*
X522861D03*
X529621D03*
X533001Y239596D03*
X539761D03*
X478922D03*
X485682D03*
X492442D03*
X499202D03*
X505962D03*
X512722D03*
X519481D03*
X526241D03*
X536381Y237647D03*
X482302D03*
X489062D03*
X495822D03*
X502582D03*
X509342D03*
X516102D03*
X522861D03*
X529621D03*
X533001Y235696D03*
X539761D03*
X478922D03*
X485682D03*
X492442D03*
X499202D03*
X505962D03*
X512722D03*
X519481D03*
X526241D03*
X536381Y233746D03*
X482302D03*
X489062D03*
X495822D03*
X502582D03*
X509342D03*
X516102D03*
X522861D03*
X529621D03*
X533001Y231797D03*
X539761D03*
X478922D03*
X485682D03*
X492442D03*
X499202D03*
X505962D03*
X512722D03*
X519481D03*
X526241D03*
X533001Y227896D03*
X539761D03*
X478922D03*
X485682D03*
X492442D03*
X499202D03*
X505962D03*
X512722D03*
X519481D03*
X526241D03*
X536381Y225947D03*
X482302D03*
X489062D03*
X495822D03*
X502582D03*
X509342D03*
X516102D03*
X522861D03*
X529621D03*
X533001Y223996D03*
X539761D03*
X478922D03*
X485682D03*
X492442D03*
X499202D03*
X505962D03*
X512722D03*
X519481D03*
X526241D03*
X536381Y222047D03*
X482302D03*
X489062D03*
X495822D03*
X502582D03*
X509342D03*
X516102D03*
X522861D03*
X529621D03*
X533001Y220096D03*
X539761D03*
X478922D03*
X485682D03*
X492442D03*
X499202D03*
X505962D03*
X512722D03*
X519481D03*
X526241D03*
X533001Y278596D03*
X539761D03*
X478922D03*
X485682D03*
X492442D03*
X499202D03*
X505962D03*
X512722D03*
X519481D03*
X526241D03*
X536381Y276646D03*
X482302D03*
X489062D03*
X495822D03*
X502582D03*
X509342D03*
X516102D03*
X522861D03*
X529621D03*
X533001Y274696D03*
X539761D03*
X478922D03*
X485682D03*
X492442D03*
X499202D03*
X505962D03*
X512722D03*
X519481D03*
X526241D03*
X536381Y272747D03*
X482302D03*
X489062D03*
X495822D03*
X502582D03*
X509342D03*
X516102D03*
X522861D03*
X529621D03*
X533001Y270796D03*
X539761D03*
X478922D03*
X485682D03*
X492442D03*
X499202D03*
X505962D03*
X512722D03*
X519481D03*
X526241D03*
X536381Y268847D03*
X482302D03*
X489062D03*
X495822D03*
X502582D03*
X509342D03*
X516102D03*
X522861D03*
X529621D03*
X533001Y266896D03*
X539761D03*
X478922D03*
X485682D03*
X492442D03*
X499202D03*
X505962D03*
X519481D03*
X526241D03*
X536381Y264947D03*
X482302D03*
X489062D03*
X495822D03*
X502582D03*
X516102D03*
X522861D03*
X529621D03*
X533001Y262996D03*
X539761D03*
X478922D03*
X485682D03*
X492442D03*
X499202D03*
X519481D03*
X526241D03*
X536381Y261047D03*
X482302D03*
X489062D03*
X495822D03*
X502582D03*
X516102D03*
X522861D03*
X529621D03*
X533001Y259096D03*
X539761D03*
X478922D03*
X485682D03*
X492442D03*
X499202D03*
X519481D03*
X526241D03*
X536381Y257147D03*
X482302D03*
X489062D03*
X495822D03*
X502582D03*
X516102D03*
X522861D03*
X529621D03*
X533001Y255196D03*
X539761D03*
X478922D03*
X485682D03*
X492442D03*
X499202D03*
X512722D03*
X519481D03*
X526241D03*
X536381Y253247D03*
X482302D03*
X489062D03*
X495822D03*
X502582D03*
X509342D03*
X516102D03*
X522861D03*
X529621D03*
X533001Y251296D03*
X539761D03*
X478922D03*
X485682D03*
X492442D03*
X499202D03*
X505962D03*
X512722D03*
X519481D03*
X526241D03*
X536381Y249347D03*
X482302D03*
X489062D03*
X495822D03*
X502582D03*
X509342D03*
X516102D03*
X522861D03*
X529621D03*
X533001Y247396D03*
X539761D03*
X478922D03*
X485682D03*
X492442D03*
X499202D03*
X505962D03*
X512722D03*
X519481D03*
X526241D03*
X536381Y245447D03*
X482302D03*
X489062D03*
X495822D03*
X502582D03*
X509342D03*
X516102D03*
X522861D03*
X529621D03*
X533001Y243496D03*
X539761D03*
X478922D03*
X485682D03*
X492442D03*
X499202D03*
X505962D03*
X512722D03*
X519481D03*
X526241D03*
X536381Y241547D03*
X482302D03*
X489062D03*
X495822D03*
X502582D03*
X509342D03*
X516102D03*
X522861D03*
X529621D03*
X536381Y229847D03*
X482302D03*
X489062D03*
X495822D03*
X502582D03*
X509342D03*
X516102D03*
X522861D03*
X529621D03*
X533001Y340996D03*
X539761D03*
X478922D03*
X485682D03*
X492442D03*
X499202D03*
X512722D03*
X519481D03*
X526241D03*
X536381Y339047D03*
X482302D03*
X489062D03*
X495822D03*
X502582D03*
X509342D03*
X516102D03*
X522861D03*
X529621D03*
X533001Y337096D03*
X539761D03*
X478922D03*
X485682D03*
X492442D03*
X499202D03*
X505962D03*
X512722D03*
X519481D03*
X526241D03*
X536381Y335147D03*
X482302D03*
X489062D03*
X495822D03*
X502582D03*
X509342D03*
X516102D03*
X522861D03*
X529621D03*
X533001Y333196D03*
X539761D03*
X478922D03*
X485682D03*
X492442D03*
X499202D03*
X505962D03*
X512722D03*
X519481D03*
X526241D03*
X536381Y331247D03*
X482302D03*
X489062D03*
X495822D03*
X502582D03*
X509342D03*
X516102D03*
X522861D03*
X529621D03*
X533001Y329296D03*
X539761D03*
X478922D03*
X485682D03*
X492442D03*
X499202D03*
X505962D03*
X512722D03*
X519481D03*
X526241D03*
X536381Y327347D03*
X482302D03*
X489062D03*
X495822D03*
X502582D03*
X509342D03*
X516102D03*
X522861D03*
X529621D03*
X533001Y325396D03*
X539761D03*
X478922D03*
X485682D03*
X492442D03*
X499202D03*
X505962D03*
X512722D03*
X519481D03*
X526241D03*
X536381Y323446D03*
X482302D03*
X489062D03*
X495822D03*
X502582D03*
X509342D03*
X516102D03*
X522861D03*
X529621D03*
X533001Y321496D03*
X539761D03*
X478922D03*
X485682D03*
X492442D03*
X499202D03*
X505962D03*
X512722D03*
X519481D03*
X526241D03*
X536381Y319547D03*
X482302D03*
X489062D03*
X495822D03*
X502582D03*
X509342D03*
X516102D03*
X522861D03*
X529621D03*
X533001Y317596D03*
X539761D03*
X478922D03*
X485682D03*
X492442D03*
X499202D03*
X505962D03*
X512722D03*
X519481D03*
X526241D03*
X536381Y315647D03*
X482302D03*
X489062D03*
X495822D03*
X502582D03*
X509342D03*
X516102D03*
X522861D03*
X529621D03*
X533001Y313696D03*
X539761D03*
X478922D03*
X485682D03*
X492442D03*
X499202D03*
X505962D03*
X512722D03*
X519481D03*
X526241D03*
X536381Y311747D03*
X482302D03*
X489062D03*
X495822D03*
X502582D03*
X509342D03*
X516102D03*
X522861D03*
X529621D03*
X533001Y309797D03*
X539761D03*
X478922D03*
X485682D03*
X492442D03*
X499202D03*
X505962D03*
X512722D03*
X519481D03*
X526241D03*
X536381Y307847D03*
X482302D03*
X489062D03*
X495822D03*
X502582D03*
X509342D03*
X516102D03*
X522861D03*
X529621D03*
X533001Y305896D03*
X539761D03*
X478922D03*
X485682D03*
X492442D03*
X499202D03*
X505962D03*
X512722D03*
X519481D03*
X526241D03*
X536381Y303947D03*
X482302D03*
X489062D03*
X495822D03*
X502582D03*
X509342D03*
X516102D03*
X522861D03*
X529621D03*
X533001Y301996D03*
X539761D03*
X478922D03*
X485682D03*
X492442D03*
X499202D03*
X505962D03*
X512722D03*
X519481D03*
X526241D03*
X536381Y300047D03*
X482302D03*
X489062D03*
X495822D03*
X502582D03*
X509342D03*
X516102D03*
X522861D03*
X529621D03*
X533001Y298096D03*
X539761D03*
X478922D03*
X485682D03*
X492442D03*
X499202D03*
X505962D03*
X512722D03*
X519481D03*
X526241D03*
X536381Y296147D03*
X482302D03*
X489062D03*
X495822D03*
X502582D03*
X509342D03*
X516102D03*
X522861D03*
X529621D03*
X533001Y294196D03*
X539761D03*
X478922D03*
X485682D03*
X492442D03*
X499202D03*
X505962D03*
X512722D03*
X519481D03*
X526241D03*
X536381Y292247D03*
X482302D03*
X489062D03*
X495822D03*
X502582D03*
X509342D03*
X516102D03*
X522861D03*
X529621D03*
X533001Y290296D03*
X539761D03*
X478922D03*
X485682D03*
X492442D03*
X499202D03*
X505962D03*
X512722D03*
X519481D03*
X526241D03*
X536381Y288347D03*
X482302D03*
X489062D03*
X495822D03*
X502582D03*
X509342D03*
X516102D03*
X522861D03*
X529621D03*
X533001Y286396D03*
X539761D03*
X478922D03*
X485682D03*
X492442D03*
X499202D03*
X505962D03*
X512722D03*
X519481D03*
X526241D03*
X536381Y284447D03*
X482302D03*
X489062D03*
X495822D03*
X502582D03*
X509342D03*
X516102D03*
X522861D03*
X529621D03*
X533001Y282496D03*
X539761D03*
X478922D03*
X485682D03*
X492442D03*
X499202D03*
X505962D03*
X512722D03*
X519481D03*
X526241D03*
X536381Y280547D03*
X482302D03*
X489062D03*
X495822D03*
X502582D03*
X509342D03*
X516102D03*
X522861D03*
X529621D03*
X533001Y403396D03*
X539761D03*
X478922D03*
X485682D03*
X512722D03*
X519481D03*
X526241D03*
X536381Y401447D03*
X482302D03*
X489062D03*
X509342D03*
X516102D03*
X522861D03*
X529621D03*
X533001Y399496D03*
X539761D03*
X478922D03*
X485682D03*
X492442D03*
X512722D03*
X519481D03*
X526241D03*
X536381Y397546D03*
X482302D03*
X489062D03*
X495822D03*
X502582D03*
X509342D03*
X516102D03*
X522861D03*
X529621D03*
X533001Y395597D03*
X539761D03*
X478922D03*
X485682D03*
X492442D03*
X499202D03*
X505962D03*
X512722D03*
X519481D03*
X526241D03*
X536381Y393647D03*
X482302D03*
X489062D03*
X495822D03*
X502582D03*
X509342D03*
X516102D03*
X522861D03*
X529621D03*
X533001Y391696D03*
X539761D03*
X478922D03*
X485682D03*
X492442D03*
X499202D03*
X505962D03*
X512722D03*
X519481D03*
X526241D03*
X536381Y389747D03*
X482302D03*
X489062D03*
X495822D03*
X502582D03*
X509342D03*
X516102D03*
X522861D03*
X529621D03*
X533001Y387796D03*
X539761D03*
X478922D03*
X485682D03*
X492442D03*
X499202D03*
X505962D03*
X512722D03*
X519481D03*
X526241D03*
X536381Y385847D03*
X482302D03*
X489062D03*
X495822D03*
X502582D03*
X509342D03*
X516102D03*
X522861D03*
X529621D03*
X533001Y383896D03*
X539761D03*
X478922D03*
X485682D03*
X492442D03*
X499202D03*
X505962D03*
X512722D03*
X519481D03*
X526241D03*
X536381Y381947D03*
X482302D03*
X489062D03*
X495822D03*
X502582D03*
X509342D03*
X516102D03*
X522861D03*
X529621D03*
X536381Y378047D03*
X482302D03*
X489062D03*
X495822D03*
X502582D03*
X509342D03*
X516102D03*
X522861D03*
X529621D03*
X533001Y376096D03*
X539761D03*
X478922D03*
X485682D03*
X492442D03*
X499202D03*
X505962D03*
X512722D03*
X519481D03*
X526241D03*
X536381Y374146D03*
X482302D03*
X489062D03*
X495822D03*
X502582D03*
X509342D03*
X516102D03*
X522861D03*
X529621D03*
X533001Y372197D03*
X539761D03*
X478922D03*
X485682D03*
X492442D03*
X499202D03*
X505962D03*
X512722D03*
X519481D03*
X526241D03*
X536381Y370247D03*
X482302D03*
X489062D03*
X495822D03*
X502582D03*
X509342D03*
X516102D03*
X522861D03*
X529621D03*
X533001Y368296D03*
X539761D03*
X478922D03*
X485682D03*
X492442D03*
X499202D03*
X505962D03*
X512722D03*
X519481D03*
X526241D03*
X536381Y366347D03*
X482302D03*
X489062D03*
X495822D03*
X502582D03*
X509342D03*
X516102D03*
X522861D03*
X529621D03*
X533001Y364396D03*
X539761D03*
X478922D03*
X485682D03*
X492442D03*
X499202D03*
X505962D03*
X512722D03*
X519481D03*
X526241D03*
X536381Y362447D03*
X482302D03*
X489062D03*
X495822D03*
X502582D03*
X509342D03*
X516102D03*
X522861D03*
X529621D03*
X533001Y360496D03*
X539761D03*
X478922D03*
X485682D03*
X492442D03*
X499202D03*
X505962D03*
X512722D03*
X519481D03*
X526241D03*
X536381Y358547D03*
X482302D03*
X489062D03*
X495822D03*
X502582D03*
X509342D03*
X516102D03*
X522861D03*
X529621D03*
X533001Y356596D03*
X539761D03*
X478922D03*
X485682D03*
X492442D03*
X499202D03*
X505962D03*
X512722D03*
X519481D03*
X526241D03*
X536381Y354647D03*
X482302D03*
X489062D03*
X495822D03*
X502582D03*
X509342D03*
X516102D03*
X522861D03*
X529621D03*
X533001Y352696D03*
X539761D03*
X478922D03*
X485682D03*
X492442D03*
X499202D03*
X505962D03*
X519481D03*
X526241D03*
X536381Y350747D03*
X482302D03*
X489062D03*
X495822D03*
X502582D03*
X516102D03*
X522861D03*
X529621D03*
X533001Y348796D03*
X539761D03*
X478922D03*
X485682D03*
X492442D03*
X499202D03*
X519481D03*
X526241D03*
X536381Y346847D03*
X482302D03*
X489062D03*
X495822D03*
X502582D03*
X516102D03*
X522861D03*
X529621D03*
X533001Y344896D03*
X539761D03*
X478922D03*
X485682D03*
X492442D03*
X499202D03*
X519481D03*
X526241D03*
X536381Y342947D03*
X482302D03*
X489062D03*
X495822D03*
X502582D03*
X516102D03*
X522861D03*
X529621D03*
X533001Y379996D03*
X539761D03*
X478922D03*
X485682D03*
X492442D03*
X499202D03*
X505962D03*
X512722D03*
X519481D03*
X526241D03*
X536381Y405347D03*
X482302D03*
X509342D03*
X516102D03*
X522861D03*
X529621D03*
X543141Y218147D03*
X549901D03*
X556661D03*
X546521Y216196D03*
X553281D03*
X560041D03*
X543141Y214247D03*
X549901D03*
X556661D03*
X546521Y212296D03*
X553281D03*
X543141Y210346D03*
X549901D03*
X556661D03*
X546521Y208397D03*
X553281D03*
X543141Y206447D03*
X549901D03*
X546521Y204496D03*
X553281D03*
X543141Y202547D03*
X549901D03*
X546521Y239596D03*
X553281D03*
X560041D03*
X543141Y237647D03*
X549901D03*
X556661D03*
X546521Y235696D03*
X553281D03*
X560041D03*
X543141Y233746D03*
X549901D03*
X556661D03*
X546521Y231797D03*
X553281D03*
X560041D03*
X546521Y227896D03*
X553281D03*
X560041D03*
X543141Y225947D03*
X549901D03*
X556661D03*
X546521Y223996D03*
X553281D03*
X560041D03*
X543141Y222047D03*
X549901D03*
X556661D03*
X546521Y220096D03*
X553281D03*
X560041D03*
X546521Y278596D03*
X553281D03*
X543141Y276646D03*
X549901D03*
X556661D03*
X546521Y274696D03*
X553281D03*
X560041D03*
X543141Y272747D03*
X549901D03*
X556661D03*
X546521Y270796D03*
X553281D03*
X560041D03*
X543141Y268847D03*
X549901D03*
X556661D03*
X546521Y266896D03*
X553281D03*
X560041D03*
X543141Y264947D03*
X549901D03*
X556661D03*
X546521Y262996D03*
X553281D03*
X560041D03*
X543141Y261047D03*
X549901D03*
X556661D03*
X546521Y259096D03*
X553281D03*
X560041D03*
X543141Y257147D03*
X549901D03*
X556661D03*
X546521Y255196D03*
X553281D03*
X560041D03*
X543141Y253247D03*
X549901D03*
X556661D03*
X546521Y251296D03*
X553281D03*
X560041D03*
X543141Y249347D03*
X549901D03*
X556661D03*
X546521Y247396D03*
X553281D03*
X560041D03*
X543141Y245447D03*
X549901D03*
X556661D03*
X546521Y243496D03*
X553281D03*
X560041D03*
X543141Y241547D03*
X549901D03*
X556661D03*
X543141Y229847D03*
X549901D03*
X556661D03*
X546521Y340996D03*
X553281D03*
X560041D03*
X543141Y339047D03*
X549901D03*
X556661D03*
X546521Y337096D03*
X553281D03*
X560041D03*
X543141Y335147D03*
X549901D03*
X556661D03*
X546521Y333196D03*
X553281D03*
X560041D03*
X543141Y331247D03*
X549901D03*
X556661D03*
X546521Y329296D03*
X553281D03*
X543141Y327347D03*
X549901D03*
X556661D03*
X546521Y325396D03*
X553281D03*
X543141Y323446D03*
X549901D03*
X556661D03*
X546521Y321496D03*
X553281D03*
X543141Y319547D03*
X549901D03*
X556661D03*
X546521Y317596D03*
X553281D03*
X543141Y315647D03*
X549901D03*
X546521Y313696D03*
X553281D03*
X543141Y311747D03*
X549901D03*
X546521Y309797D03*
X553281D03*
X543141Y307847D03*
X549901D03*
X546521Y305896D03*
X553281D03*
X543141Y303947D03*
X549901D03*
X546521Y301996D03*
X553281D03*
X543141Y300047D03*
X549901D03*
X546521Y298096D03*
X553281D03*
X543141Y296147D03*
X549901D03*
X546521Y294196D03*
X553281D03*
X543141Y292247D03*
X549901D03*
X546521Y290296D03*
X553281D03*
X543141Y288347D03*
X549901D03*
X546521Y286396D03*
X553281D03*
X543141Y284447D03*
X549901D03*
X556661D03*
X546521Y282496D03*
X553281D03*
X543141Y280547D03*
X549901D03*
X556661D03*
X546521Y403396D03*
X543141Y401447D03*
X549901D03*
X546521Y399496D03*
X553281D03*
X543141Y397546D03*
X549901D03*
X546521Y395597D03*
X553281D03*
X543141Y393647D03*
X549901D03*
X556661D03*
X546521Y391696D03*
X553281D03*
X543141Y389747D03*
X549901D03*
X556661D03*
X546521Y387796D03*
X553281D03*
X543141Y385847D03*
X549901D03*
X556661D03*
X546521Y383896D03*
X553281D03*
X543141Y381947D03*
X549901D03*
X556661D03*
X543141Y378047D03*
X549901D03*
X556661D03*
X546521Y376096D03*
X553281D03*
X543141Y374146D03*
X549901D03*
X556661D03*
X546521Y372197D03*
X553281D03*
X543141Y370247D03*
X549901D03*
X556661D03*
X546521Y368296D03*
X553281D03*
X543141Y366347D03*
X549901D03*
X556661D03*
X546521Y364396D03*
X553281D03*
X543141Y362447D03*
X549901D03*
X556661D03*
X546521Y360496D03*
X553281D03*
X560041D03*
X543141Y358547D03*
X549901D03*
X556661D03*
X546521Y356596D03*
X553281D03*
X560041D03*
X543141Y354647D03*
X549901D03*
X556661D03*
X546521Y352696D03*
X553281D03*
X560041D03*
X543141Y350747D03*
X549901D03*
X556661D03*
X546521Y348796D03*
X553281D03*
X560041D03*
X543141Y346847D03*
X549901D03*
X556661D03*
X546521Y344896D03*
X553281D03*
X560041D03*
X543141Y342947D03*
X549901D03*
X556661D03*
X546521Y379996D03*
X553281D03*
X543141Y405347D03*
X919717Y216909D03*
X926477D03*
X933237D03*
X939997D03*
X946757D03*
X953517D03*
X960276D03*
X967036D03*
X916337Y214960D03*
X923097D03*
X929857D03*
X936617D03*
X943377D03*
X950137D03*
X956897D03*
X963656D03*
X970416D03*
X919717Y213009D03*
X926477D03*
X933237D03*
X939997D03*
X946757D03*
X953517D03*
X960276D03*
X967036D03*
X916337Y211060D03*
X923097D03*
X929857D03*
X936617D03*
X943377D03*
X950137D03*
X956897D03*
X963656D03*
X970416D03*
X919717Y209109D03*
X926477D03*
X933237D03*
X939997D03*
X946757D03*
X953517D03*
X960276D03*
X967036D03*
X923097Y207159D03*
X929857D03*
X936617D03*
X943377D03*
X950137D03*
X956897D03*
X963656D03*
X970416D03*
X926477Y205210D03*
X933237D03*
X939997D03*
X946757D03*
X953517D03*
X960276D03*
X967036D03*
X923097Y203260D03*
X929857D03*
X936617D03*
X943377D03*
X950137D03*
X956897D03*
X963656D03*
X926477Y201309D03*
X933237D03*
X939997D03*
X946757D03*
X953517D03*
X960276D03*
X967036D03*
X929857Y199360D03*
X936617D03*
X943377D03*
X950137D03*
X956897D03*
X963656D03*
X933237Y197409D03*
X939997D03*
X946757D03*
X953517D03*
X960276D03*
X967036D03*
X919717Y232509D03*
X926477D03*
X933237D03*
X939997D03*
X946757D03*
X953517D03*
X960276D03*
X967036D03*
X916337Y230559D03*
X923097D03*
X929857D03*
X936617D03*
X943377D03*
X950137D03*
X956897D03*
X963656D03*
X970416D03*
X919717Y228610D03*
X926477D03*
X933237D03*
X939997D03*
X946757D03*
X953517D03*
X960276D03*
X967036D03*
X916337Y226660D03*
X923097D03*
X929857D03*
X936617D03*
X943377D03*
X950137D03*
X956897D03*
X963656D03*
X970416D03*
X919717Y224709D03*
X926477D03*
X933237D03*
X939997D03*
X946757D03*
X953517D03*
X960276D03*
X967036D03*
X919717Y220809D03*
X926477D03*
X933237D03*
X939997D03*
X946757D03*
X953517D03*
X960276D03*
X967036D03*
X916337Y218860D03*
X923097D03*
X929857D03*
X936617D03*
X943377D03*
X950137D03*
X956897D03*
X963656D03*
X970416D03*
X919717Y279310D03*
X926477D03*
X933237D03*
X939997D03*
X946757D03*
X953517D03*
X960276D03*
X967036D03*
X923097Y277360D03*
X929857D03*
X936617D03*
X943377D03*
X950137D03*
X956897D03*
X963656D03*
X970416D03*
X919717Y275409D03*
X926477D03*
X933237D03*
X939997D03*
X946757D03*
X953517D03*
X960276D03*
X967036D03*
X916337Y273460D03*
X923097D03*
X929857D03*
X936617D03*
X943377D03*
X950137D03*
X956897D03*
X963656D03*
X970416D03*
X919717Y271509D03*
X926477D03*
X933237D03*
X939997D03*
X946757D03*
X953517D03*
X960276D03*
X967036D03*
X916337Y269560D03*
X923097D03*
X929857D03*
X936617D03*
X943377D03*
X950137D03*
X956897D03*
X963656D03*
X970416D03*
X919717Y267609D03*
X926477D03*
X933237D03*
X939997D03*
X946757D03*
X953517D03*
X960276D03*
X967036D03*
X916337Y265660D03*
X923097D03*
X929857D03*
X936617D03*
X943377D03*
X950137D03*
X956897D03*
X963656D03*
X970416D03*
X919717Y263709D03*
X926477D03*
X933237D03*
X939997D03*
X946757D03*
X953517D03*
X960276D03*
X967036D03*
X916337Y261760D03*
X923097D03*
X929857D03*
X936617D03*
X943377D03*
X950137D03*
X956897D03*
X963656D03*
X919717Y259809D03*
X926477D03*
X933237D03*
X939997D03*
X946757D03*
X953517D03*
X960276D03*
X916337Y257860D03*
X923097D03*
X929857D03*
X936617D03*
X943377D03*
X950137D03*
X956897D03*
X919717Y255909D03*
X926477D03*
X933237D03*
X939997D03*
X946757D03*
X953517D03*
X960276D03*
X916337Y253960D03*
X923097D03*
X929857D03*
X936617D03*
X943377D03*
X950137D03*
X956897D03*
X919717Y252009D03*
X926477D03*
X933237D03*
X939997D03*
X946757D03*
X953517D03*
X960276D03*
X916337Y250060D03*
X923097D03*
X929857D03*
X936617D03*
X943377D03*
X950137D03*
X956897D03*
X970416D03*
X919717Y248109D03*
X926477D03*
X933237D03*
X939997D03*
X946757D03*
X953517D03*
X960276D03*
X967036D03*
X916337Y246160D03*
X923097D03*
X929857D03*
X936617D03*
X943377D03*
X950137D03*
X956897D03*
X963656D03*
X970416D03*
X919717Y244209D03*
X926477D03*
X933237D03*
X939997D03*
X946757D03*
X953517D03*
X960276D03*
X967036D03*
X916337Y242260D03*
X923097D03*
X929857D03*
X936617D03*
X943377D03*
X950137D03*
X956897D03*
X963656D03*
X970416D03*
X919717Y240309D03*
X926477D03*
X933237D03*
X939997D03*
X946757D03*
X953517D03*
X960276D03*
X967036D03*
X916337Y238360D03*
X923097D03*
X929857D03*
X936617D03*
X943377D03*
X950137D03*
X956897D03*
X963656D03*
X970416D03*
X919717Y236409D03*
X926477D03*
X933237D03*
X939997D03*
X946757D03*
X953517D03*
X960276D03*
X967036D03*
X916337Y234460D03*
X923097D03*
X929857D03*
X936617D03*
X943377D03*
X950137D03*
X956897D03*
X963656D03*
X970416D03*
X916337Y222760D03*
X923097D03*
X929857D03*
X936617D03*
X943377D03*
X950137D03*
X956897D03*
X963656D03*
X970416D03*
X919717Y341709D03*
X926477D03*
X933237D03*
X939997D03*
X946757D03*
X953517D03*
X960276D03*
X916337Y339760D03*
X923097D03*
X929857D03*
X936617D03*
X943377D03*
X950137D03*
X956897D03*
X919717Y337809D03*
X926477D03*
X933237D03*
X939997D03*
X946757D03*
X953517D03*
X960276D03*
X916337Y335860D03*
X923097D03*
X929857D03*
X936617D03*
X943377D03*
X950137D03*
X956897D03*
X970416D03*
X919717Y333909D03*
X926477D03*
X933237D03*
X939997D03*
X946757D03*
X953517D03*
X960276D03*
X967036D03*
X916337Y331960D03*
X923097D03*
X929857D03*
X936617D03*
X943377D03*
X950137D03*
X956897D03*
X963656D03*
X970416D03*
X919717Y330009D03*
X926477D03*
X933237D03*
X939997D03*
X946757D03*
X953517D03*
X960276D03*
X967036D03*
X916337Y328060D03*
X923097D03*
X929857D03*
X936617D03*
X943377D03*
X950137D03*
X956897D03*
X963656D03*
X970416D03*
X919717Y326110D03*
X926477D03*
X933237D03*
X939997D03*
X946757D03*
X953517D03*
X960276D03*
X967036D03*
X923097Y324160D03*
X929857D03*
X936617D03*
X943377D03*
X950137D03*
X956897D03*
X963656D03*
X970416D03*
X919717Y322209D03*
X926477D03*
X933237D03*
X939997D03*
X946757D03*
X953517D03*
X960276D03*
X967036D03*
X923097Y320260D03*
X929857D03*
X936617D03*
X943377D03*
X950137D03*
X956897D03*
X963656D03*
X970416D03*
X919717Y318309D03*
X926477D03*
X933237D03*
X939997D03*
X946757D03*
X953517D03*
X960276D03*
X967036D03*
X923097Y316360D03*
X929857D03*
X936617D03*
X943377D03*
X950137D03*
X956897D03*
X963656D03*
X970416D03*
X926477Y314409D03*
X933237D03*
X939997D03*
X946757D03*
X953517D03*
X960276D03*
X967036D03*
X923097Y312460D03*
X929857D03*
X936617D03*
X943377D03*
X950137D03*
X956897D03*
X963656D03*
X970416D03*
X926477Y310509D03*
X933237D03*
X939997D03*
X946757D03*
X953517D03*
X960276D03*
X967036D03*
X923097Y308560D03*
X929857D03*
X936617D03*
X943377D03*
X950137D03*
X956897D03*
X963656D03*
X970416D03*
X926477Y306609D03*
X933237D03*
X939997D03*
X946757D03*
X953517D03*
X960276D03*
X967036D03*
X923097Y304660D03*
X929857D03*
X936617D03*
X943377D03*
X950137D03*
X956897D03*
X963656D03*
X970416D03*
X926477Y302709D03*
X933237D03*
X939997D03*
X946757D03*
X953517D03*
X960276D03*
X967036D03*
X923097Y300760D03*
X929857D03*
X936617D03*
X943377D03*
X950137D03*
X956897D03*
X963656D03*
X970416D03*
X926477Y298809D03*
X933237D03*
X939997D03*
X946757D03*
X953517D03*
X960276D03*
X967036D03*
X923097Y296860D03*
X929857D03*
X936617D03*
X943377D03*
X950137D03*
X956897D03*
X963656D03*
X970416D03*
X926477Y294909D03*
X933237D03*
X939997D03*
X946757D03*
X953517D03*
X960276D03*
X967036D03*
X923097Y292959D03*
X929857D03*
X936617D03*
X943377D03*
X950137D03*
X956897D03*
X963656D03*
X970416D03*
X926477Y291009D03*
X933237D03*
X939997D03*
X946757D03*
X953517D03*
X960276D03*
X967036D03*
X923097Y289060D03*
X929857D03*
X936617D03*
X943377D03*
X950137D03*
X956897D03*
X963656D03*
X970416D03*
X926477Y287109D03*
X933237D03*
X939997D03*
X946757D03*
X953517D03*
X960276D03*
X967036D03*
X923097Y285160D03*
X929857D03*
X936617D03*
X943377D03*
X950137D03*
X956897D03*
X963656D03*
X970416D03*
X919717Y283209D03*
X926477D03*
X933237D03*
X939997D03*
X946757D03*
X953517D03*
X960276D03*
X967036D03*
X923097Y281260D03*
X929857D03*
X936617D03*
X943377D03*
X950137D03*
X956897D03*
X963656D03*
X970416D03*
X926477Y400209D03*
X933237D03*
X939997D03*
X946757D03*
X953517D03*
X960276D03*
X967036D03*
X923097Y398260D03*
X929857D03*
X936617D03*
X943377D03*
X950137D03*
X956897D03*
X963656D03*
X970416D03*
X926477Y396309D03*
X933237D03*
X939997D03*
X946757D03*
X953517D03*
X960276D03*
X967036D03*
X923097Y394359D03*
X929857D03*
X936617D03*
X943377D03*
X950137D03*
X956897D03*
X963656D03*
X970416D03*
X919717Y392410D03*
X926477D03*
X933237D03*
X939997D03*
X946757D03*
X953517D03*
X960276D03*
X967036D03*
X923097Y390460D03*
X929857D03*
X936617D03*
X943377D03*
X950137D03*
X956897D03*
X963656D03*
X970416D03*
X919717Y388509D03*
X926477D03*
X933237D03*
X939997D03*
X946757D03*
X953517D03*
X960276D03*
X967036D03*
X923097Y386560D03*
X929857D03*
X936617D03*
X943377D03*
X950137D03*
X956897D03*
X963656D03*
X970416D03*
X919717Y384609D03*
X926477D03*
X933237D03*
X939997D03*
X946757D03*
X953517D03*
X960276D03*
X967036D03*
X923097Y382660D03*
X929857D03*
X936617D03*
X943377D03*
X950137D03*
X956897D03*
X963656D03*
X970416D03*
X919717Y380709D03*
X926477D03*
X933237D03*
X939997D03*
X946757D03*
X953517D03*
X960276D03*
X967036D03*
X923097Y378760D03*
X929857D03*
X936617D03*
X943377D03*
X950137D03*
X956897D03*
X963656D03*
X970416D03*
X919717Y376809D03*
X926477D03*
X933237D03*
X939997D03*
X946757D03*
X953517D03*
X960276D03*
X967036D03*
X923097Y374860D03*
X929857D03*
X936617D03*
X943377D03*
X950137D03*
X956897D03*
X963656D03*
X970416D03*
X923097Y370959D03*
X929857D03*
X936617D03*
X943377D03*
X950137D03*
X956897D03*
X963656D03*
X970416D03*
X919717Y369010D03*
X926477D03*
X933237D03*
X939997D03*
X946757D03*
X953517D03*
X960276D03*
X967036D03*
X923097Y367060D03*
X929857D03*
X936617D03*
X943377D03*
X950137D03*
X956897D03*
X963656D03*
X970416D03*
X919717Y365109D03*
X926477D03*
X933237D03*
X939997D03*
X946757D03*
X953517D03*
X960276D03*
X967036D03*
X923097Y363160D03*
X929857D03*
X936617D03*
X943377D03*
X950137D03*
X956897D03*
X963656D03*
X970416D03*
X919717Y361209D03*
X926477D03*
X933237D03*
X939997D03*
X946757D03*
X953517D03*
X960276D03*
X967036D03*
X923097Y359260D03*
X929857D03*
X936617D03*
X943377D03*
X950137D03*
X956897D03*
X963656D03*
X970416D03*
X919717Y357309D03*
X926477D03*
X933237D03*
X939997D03*
X946757D03*
X953517D03*
X960276D03*
X967036D03*
X916337Y355360D03*
X923097D03*
X929857D03*
X936617D03*
X943377D03*
X950137D03*
X956897D03*
X963656D03*
X970416D03*
X919717Y353409D03*
X926477D03*
X933237D03*
X939997D03*
X946757D03*
X953517D03*
X960276D03*
X967036D03*
X916337Y351460D03*
X923097D03*
X929857D03*
X936617D03*
X943377D03*
X950137D03*
X956897D03*
X963656D03*
X970416D03*
X919717Y349509D03*
X926477D03*
X933237D03*
X939997D03*
X946757D03*
X953517D03*
X960276D03*
X967036D03*
X916337Y347560D03*
X923097D03*
X929857D03*
X936617D03*
X943377D03*
X950137D03*
X956897D03*
X963656D03*
X919717Y345609D03*
X926477D03*
X933237D03*
X939997D03*
X946757D03*
X953517D03*
X960276D03*
X916337Y343660D03*
X923097D03*
X929857D03*
X936617D03*
X943377D03*
X950137D03*
X956897D03*
X919717Y372909D03*
X926477D03*
X933237D03*
X939997D03*
X946757D03*
X953517D03*
X960276D03*
X967036D03*
X973796Y216909D03*
X980556D03*
X987316D03*
X994076D03*
X1000836D03*
X1007595D03*
X1014355D03*
X1021115D03*
X1027875D03*
X977176Y214960D03*
X983936D03*
X990696D03*
X997456D03*
X1004215D03*
X1010975D03*
X1017735D03*
X1024495D03*
X1031255D03*
X973796Y213009D03*
X980556D03*
X987316D03*
X994076D03*
X1000836D03*
X1007595D03*
X1014355D03*
X1021115D03*
X1027875D03*
X977176Y211060D03*
X983936D03*
X990696D03*
X997456D03*
X1004215D03*
X1010975D03*
X1017735D03*
X1024495D03*
X1031255D03*
X973796Y209109D03*
X980556D03*
X987316D03*
X994076D03*
X1000836D03*
X1007595D03*
X1014355D03*
X1021115D03*
X1027875D03*
X977176Y207159D03*
X983936D03*
X990696D03*
X997456D03*
X1004215D03*
X1010975D03*
X1017735D03*
X1024495D03*
X1031255D03*
X973796Y205210D03*
X980556D03*
X987316D03*
X994076D03*
X1000836D03*
X1007595D03*
X1014355D03*
X1021115D03*
X1027875D03*
X983936Y203260D03*
X990696D03*
X997456D03*
X1004215D03*
X1010975D03*
X1017735D03*
X1024495D03*
X1031255D03*
X987316Y201309D03*
X994076D03*
X1000836D03*
X1007595D03*
X1014355D03*
X1021115D03*
X1027875D03*
X990696Y199360D03*
X997456D03*
X1004215D03*
X1010975D03*
X1017735D03*
X1024495D03*
X1031255D03*
X994076Y197409D03*
X1000836D03*
X1007595D03*
X1014355D03*
X1021115D03*
X1027875D03*
X973796Y232509D03*
X980556D03*
X987316D03*
X994076D03*
X1000836D03*
X1007595D03*
X1014355D03*
X1021115D03*
X1027875D03*
X977176Y230559D03*
X983936D03*
X990696D03*
X997456D03*
X1004215D03*
X1010975D03*
X1017735D03*
X1024495D03*
X1031255D03*
X973796Y228610D03*
X980556D03*
X987316D03*
X994076D03*
X1000836D03*
X1007595D03*
X1014355D03*
X1021115D03*
X1027875D03*
X977176Y226660D03*
X983936D03*
X990696D03*
X997456D03*
X1004215D03*
X1010975D03*
X1017735D03*
X1024495D03*
X1031255D03*
X973796Y224709D03*
X980556D03*
X987316D03*
X994076D03*
X1000836D03*
X1007595D03*
X1014355D03*
X1021115D03*
X1027875D03*
X973796Y220809D03*
X980556D03*
X987316D03*
X994076D03*
X1000836D03*
X1007595D03*
X1014355D03*
X1021115D03*
X1027875D03*
X977176Y218860D03*
X983936D03*
X990696D03*
X997456D03*
X1004215D03*
X1010975D03*
X1017735D03*
X1024495D03*
X1031255D03*
X973796Y279310D03*
X980556D03*
X987316D03*
X994076D03*
X1000836D03*
X977176Y277360D03*
X983936D03*
X990696D03*
X997456D03*
X1004215D03*
X973796Y275409D03*
X980556D03*
X987316D03*
X994076D03*
X1000836D03*
X977176Y273460D03*
X983936D03*
X990696D03*
X997456D03*
X1004215D03*
X973796Y271509D03*
X980556D03*
X987316D03*
X994076D03*
X1000836D03*
X977176Y269560D03*
X983936D03*
X990696D03*
X997456D03*
X1004215D03*
X973796Y267609D03*
X980556D03*
X987316D03*
X994076D03*
X1000836D03*
X1007595D03*
X977176Y265660D03*
X983936D03*
X990696D03*
X997456D03*
X1004215D03*
X1010975D03*
X973796Y263709D03*
X980556D03*
X987316D03*
X994076D03*
X1000836D03*
X1007595D03*
X1014355D03*
X977176Y261760D03*
X983936D03*
X990696D03*
X997456D03*
X1004215D03*
X1010975D03*
X1017735D03*
X973796Y259809D03*
X980556D03*
X987316D03*
X994076D03*
X1000836D03*
X1007595D03*
X1014355D03*
X1021115D03*
X977176Y257860D03*
X983936D03*
X990696D03*
X997456D03*
X1004215D03*
X1010975D03*
X1017735D03*
X1024495D03*
X973796Y255909D03*
X980556D03*
X987316D03*
X994076D03*
X1000836D03*
X1007595D03*
X1014355D03*
X1021115D03*
X1027875D03*
X977176Y253960D03*
X983936D03*
X990696D03*
X997456D03*
X1004215D03*
X1010975D03*
X1017735D03*
X1024495D03*
X1031255D03*
X973796Y252009D03*
X980556D03*
X987316D03*
X994076D03*
X1000836D03*
X1007595D03*
X1014355D03*
X1021115D03*
X1027875D03*
X977176Y250060D03*
X983936D03*
X990696D03*
X997456D03*
X1004215D03*
X1010975D03*
X1017735D03*
X1024495D03*
X1031255D03*
X973796Y248109D03*
X980556D03*
X987316D03*
X994076D03*
X1000836D03*
X1007595D03*
X1014355D03*
X1021115D03*
X1027875D03*
X977176Y246160D03*
X983936D03*
X990696D03*
X997456D03*
X1004215D03*
X1010975D03*
X1017735D03*
X1024495D03*
X1031255D03*
X973796Y244209D03*
X980556D03*
X987316D03*
X994076D03*
X1000836D03*
X1007595D03*
X1014355D03*
X1021115D03*
X1027875D03*
X977176Y242260D03*
X983936D03*
X990696D03*
X997456D03*
X1004215D03*
X1010975D03*
X1017735D03*
X1024495D03*
X1031255D03*
X973796Y240309D03*
X980556D03*
X987316D03*
X994076D03*
X1000836D03*
X1007595D03*
X1014355D03*
X1021115D03*
X1027875D03*
X977176Y238360D03*
X983936D03*
X990696D03*
X997456D03*
X1004215D03*
X1010975D03*
X1017735D03*
X1024495D03*
X1031255D03*
X973796Y236409D03*
X980556D03*
X987316D03*
X994076D03*
X1000836D03*
X1007595D03*
X1014355D03*
X1021115D03*
X1027875D03*
X977176Y234460D03*
X983936D03*
X990696D03*
X997456D03*
X1004215D03*
X1010975D03*
X1017735D03*
X1024495D03*
X1031255D03*
X977176Y222760D03*
X983936D03*
X990696D03*
X997456D03*
X1004215D03*
X1010975D03*
X1017735D03*
X1024495D03*
X1031255D03*
X973796Y341709D03*
X980556D03*
X987316D03*
X994076D03*
X1000836D03*
X1007595D03*
X1014355D03*
X1021115D03*
X1027875D03*
X977176Y339760D03*
X983936D03*
X990696D03*
X997456D03*
X1004215D03*
X1010975D03*
X1017735D03*
X1024495D03*
X973796Y337809D03*
X980556D03*
X987316D03*
X994076D03*
X1000836D03*
X1007595D03*
X1014355D03*
X1021115D03*
X977176Y335860D03*
X983936D03*
X990696D03*
X997456D03*
X1004215D03*
X1010975D03*
X1017735D03*
X973796Y333909D03*
X980556D03*
X987316D03*
X994076D03*
X1000836D03*
X1007595D03*
X1014355D03*
X977176Y331960D03*
X983936D03*
X990696D03*
X997456D03*
X1004215D03*
X1010975D03*
X973796Y330009D03*
X980556D03*
X987316D03*
X994076D03*
X1000836D03*
X1007595D03*
X977176Y328060D03*
X983936D03*
X990696D03*
X997456D03*
X1004215D03*
X973796Y326110D03*
X980556D03*
X987316D03*
X994076D03*
X1000836D03*
X977176Y324160D03*
X983936D03*
X990696D03*
X997456D03*
X1004215D03*
X973796Y322209D03*
X980556D03*
X987316D03*
X994076D03*
X1000836D03*
X977176Y320260D03*
X983936D03*
X990696D03*
X997456D03*
X1004215D03*
X973796Y318309D03*
X980556D03*
X987316D03*
X994076D03*
X1000836D03*
X977176Y316360D03*
X983936D03*
X990696D03*
X997456D03*
X1004215D03*
X973796Y314409D03*
X980556D03*
X987316D03*
X994076D03*
X1000836D03*
X977176Y312460D03*
X983936D03*
X990696D03*
X997456D03*
X1004215D03*
X973796Y310509D03*
X980556D03*
X987316D03*
X994076D03*
X1000836D03*
X977176Y308560D03*
X983936D03*
X990696D03*
X997456D03*
X1004215D03*
X973796Y306609D03*
X980556D03*
X987316D03*
X994076D03*
X1000836D03*
X977176Y304660D03*
X983936D03*
X990696D03*
X997456D03*
X1004215D03*
X973796Y302709D03*
X980556D03*
X987316D03*
X994076D03*
X1000836D03*
X977176Y300760D03*
X983936D03*
X990696D03*
X997456D03*
X1004215D03*
X973796Y298809D03*
X980556D03*
X987316D03*
X994076D03*
X1000836D03*
X977176Y296860D03*
X983936D03*
X990696D03*
X997456D03*
X1004215D03*
X973796Y294909D03*
X980556D03*
X987316D03*
X994076D03*
X1000836D03*
X977176Y292959D03*
X983936D03*
X990696D03*
X997456D03*
X1004215D03*
X973796Y291009D03*
X980556D03*
X987316D03*
X994076D03*
X1000836D03*
X977176Y289060D03*
X983936D03*
X990696D03*
X997456D03*
X1004215D03*
X973796Y287109D03*
X980556D03*
X987316D03*
X994076D03*
X1000836D03*
X977176Y285160D03*
X983936D03*
X990696D03*
X997456D03*
X1004215D03*
X973796Y283209D03*
X980556D03*
X987316D03*
X994076D03*
X1000836D03*
X977176Y281260D03*
X983936D03*
X990696D03*
X997456D03*
X1004215D03*
X994076Y400209D03*
X1000836D03*
X1007595D03*
X1014355D03*
X1021115D03*
X1027875D03*
X997456Y398260D03*
X1004215D03*
X1010975D03*
X1017735D03*
X1024495D03*
X1031255D03*
X973796Y396309D03*
X994076D03*
X1000836D03*
X1007595D03*
X1014355D03*
X1021115D03*
X1027875D03*
X997456Y394359D03*
X1004215D03*
X1010975D03*
X1017735D03*
X1024495D03*
X1031255D03*
X973796Y392410D03*
X980556D03*
X987316D03*
X994076D03*
X1000836D03*
X1007595D03*
X1014355D03*
X1021115D03*
X1027875D03*
X977176Y390460D03*
X983936D03*
X990696D03*
X997456D03*
X1004215D03*
X1010975D03*
X1017735D03*
X1024495D03*
X1031255D03*
X973796Y388509D03*
X980556D03*
X987316D03*
X994076D03*
X1000836D03*
X1007595D03*
X1014355D03*
X1021115D03*
X1027875D03*
X977176Y386560D03*
X983936D03*
X990696D03*
X997456D03*
X1004215D03*
X1010975D03*
X1017735D03*
X1024495D03*
X1031255D03*
X973796Y384609D03*
X980556D03*
X987316D03*
X994076D03*
X1000836D03*
X1007595D03*
X1014355D03*
X1021115D03*
X1027875D03*
X977176Y382660D03*
X983936D03*
X990696D03*
X997456D03*
X1004215D03*
X1010975D03*
X1017735D03*
X1024495D03*
X1031255D03*
X973796Y380709D03*
X980556D03*
X987316D03*
X994076D03*
X1000836D03*
X1007595D03*
X1014355D03*
X1021115D03*
X1027875D03*
X977176Y378760D03*
X983936D03*
X990696D03*
X997456D03*
X1004215D03*
X1010975D03*
X1017735D03*
X1024495D03*
X1031255D03*
X973796Y376809D03*
X980556D03*
X987316D03*
X994076D03*
X1000836D03*
X1007595D03*
X1014355D03*
X1021115D03*
X1027875D03*
X977176Y374860D03*
X983936D03*
X990696D03*
X997456D03*
X1004215D03*
X1010975D03*
X1017735D03*
X1024495D03*
X1031255D03*
X977176Y370959D03*
X983936D03*
X990696D03*
X997456D03*
X1004215D03*
X1010975D03*
X1017735D03*
X1024495D03*
X1031255D03*
X973796Y369010D03*
X980556D03*
X987316D03*
X994076D03*
X1000836D03*
X1007595D03*
X1014355D03*
X1021115D03*
X1027875D03*
X977176Y367060D03*
X983936D03*
X990696D03*
X997456D03*
X1004215D03*
X1010975D03*
X1017735D03*
X1024495D03*
X1031255D03*
X973796Y365109D03*
X980556D03*
X987316D03*
X994076D03*
X1000836D03*
X1007595D03*
X1014355D03*
X1021115D03*
X1027875D03*
X977176Y363160D03*
X983936D03*
X990696D03*
X997456D03*
X1004215D03*
X1010975D03*
X1017735D03*
X1024495D03*
X1031255D03*
X973796Y361209D03*
X980556D03*
X987316D03*
X994076D03*
X1000836D03*
X1007595D03*
X1014355D03*
X1021115D03*
X1027875D03*
X977176Y359260D03*
X983936D03*
X990696D03*
X997456D03*
X1004215D03*
X1010975D03*
X1017735D03*
X1024495D03*
X1031255D03*
X973796Y357309D03*
X980556D03*
X987316D03*
X994076D03*
X1000836D03*
X1007595D03*
X1014355D03*
X1021115D03*
X1027875D03*
X977176Y355360D03*
X983936D03*
X990696D03*
X997456D03*
X1004215D03*
X1010975D03*
X1017735D03*
X1024495D03*
X1031255D03*
X973796Y353409D03*
X980556D03*
X987316D03*
X994076D03*
X1000836D03*
X1007595D03*
X1014355D03*
X1021115D03*
X1027875D03*
X977176Y351460D03*
X983936D03*
X990696D03*
X997456D03*
X1004215D03*
X1010975D03*
X1017735D03*
X1024495D03*
X1031255D03*
X973796Y349509D03*
X980556D03*
X987316D03*
X994076D03*
X1000836D03*
X1007595D03*
X1014355D03*
X1021115D03*
X1027875D03*
X977176Y347560D03*
X983936D03*
X990696D03*
X997456D03*
X1004215D03*
X1010975D03*
X1017735D03*
X1024495D03*
X1031255D03*
X973796Y345609D03*
X980556D03*
X987316D03*
X994076D03*
X1000836D03*
X1007595D03*
X1014355D03*
X1021115D03*
X1027875D03*
X977176Y343660D03*
X983936D03*
X990696D03*
X997456D03*
X1004215D03*
X1010975D03*
X1017735D03*
X1024495D03*
X1031255D03*
X973796Y372909D03*
X980556D03*
X987316D03*
X994076D03*
X1000836D03*
X1007595D03*
X1014355D03*
X1021115D03*
X1027875D03*
X1034635Y216909D03*
X1041395D03*
X1048154D03*
X1054914D03*
X1038015Y214960D03*
X1044774D03*
X1051534D03*
X1034635Y213009D03*
X1041395D03*
X1048154D03*
X1054914D03*
X1038015Y211060D03*
X1044774D03*
X1051534D03*
X1071072Y218147D03*
X1077832D03*
X1084591D03*
X1091351D03*
X1034635Y209109D03*
X1041395D03*
X1048154D03*
X1054914D03*
X1067692Y216196D03*
X1074452D03*
X1081212D03*
X1087971D03*
X1094731D03*
X1038015Y207159D03*
X1044774D03*
X1051534D03*
X1071072Y214247D03*
X1077832D03*
X1084591D03*
X1091351D03*
X1034635Y205210D03*
X1041395D03*
X1048154D03*
X1054914D03*
X1067692Y212296D03*
X1074452D03*
X1081212D03*
X1087971D03*
X1094731D03*
X1038015Y203260D03*
X1044774D03*
X1051534D03*
X1071072Y210346D03*
X1077832D03*
X1084591D03*
X1091351D03*
X1034635Y201309D03*
X1041395D03*
X1048154D03*
X1054914D03*
X1067692Y208397D03*
X1074452D03*
X1081212D03*
X1087971D03*
X1094731D03*
X1038015Y199360D03*
X1044774D03*
X1051534D03*
X1071072Y206447D03*
X1077832D03*
X1084591D03*
X1091351D03*
X1034635Y197409D03*
X1041395D03*
X1048154D03*
X1067692Y204496D03*
X1074452D03*
X1081212D03*
X1087971D03*
X1094731D03*
X1071072Y202547D03*
X1077832D03*
X1084591D03*
X1091351D03*
X1034635Y232509D03*
X1041395D03*
X1048154D03*
X1054914D03*
X1067692Y239596D03*
X1074452D03*
X1081212D03*
X1087971D03*
X1094731D03*
X1038015Y230559D03*
X1044774D03*
X1051534D03*
X1071072Y237647D03*
X1077832D03*
X1084591D03*
X1091351D03*
X1034635Y228610D03*
X1041395D03*
X1048154D03*
X1054914D03*
X1067692Y235696D03*
X1074452D03*
X1081212D03*
X1087971D03*
X1094731D03*
X1038015Y226660D03*
X1044774D03*
X1051534D03*
X1071072Y233746D03*
X1077832D03*
X1084591D03*
X1091351D03*
X1034635Y224709D03*
X1041395D03*
X1048154D03*
X1054914D03*
X1067692Y231797D03*
X1074452D03*
X1081212D03*
X1087971D03*
X1094731D03*
X1034635Y220809D03*
X1041395D03*
X1048154D03*
X1054914D03*
X1067692Y227896D03*
X1074452D03*
X1081212D03*
X1087971D03*
X1094731D03*
X1038015Y218860D03*
X1044774D03*
X1051534D03*
X1071072Y225947D03*
X1077832D03*
X1084591D03*
X1091351D03*
X1067692Y223996D03*
X1074452D03*
X1081212D03*
X1087971D03*
X1094731D03*
X1071072Y222047D03*
X1077832D03*
X1084591D03*
X1091351D03*
X1067692Y220096D03*
X1074452D03*
X1081212D03*
X1087971D03*
X1094731D03*
X1038015Y253960D03*
X1044774D03*
X1051534D03*
X1034635Y252009D03*
X1041395D03*
X1048154D03*
X1054914D03*
X1094731Y259096D03*
X1038015Y250060D03*
X1044774D03*
X1051534D03*
X1091351Y257147D03*
X1034635Y248109D03*
X1041395D03*
X1048154D03*
X1054914D03*
X1074452Y255196D03*
X1081212D03*
X1087971D03*
X1094731D03*
X1038015Y246160D03*
X1044774D03*
X1051534D03*
X1071072Y253247D03*
X1077832D03*
X1084591D03*
X1091351D03*
X1034635Y244209D03*
X1041395D03*
X1048154D03*
X1054914D03*
X1067692Y251296D03*
X1074452D03*
X1081212D03*
X1087971D03*
X1094731D03*
X1038015Y242260D03*
X1044774D03*
X1051534D03*
X1071072Y249347D03*
X1077832D03*
X1084591D03*
X1091351D03*
X1034635Y240309D03*
X1041395D03*
X1048154D03*
X1054914D03*
X1067692Y247396D03*
X1074452D03*
X1081212D03*
X1087971D03*
X1094731D03*
X1038015Y238360D03*
X1044774D03*
X1051534D03*
X1071072Y245447D03*
X1077832D03*
X1084591D03*
X1091351D03*
X1034635Y236409D03*
X1041395D03*
X1048154D03*
X1054914D03*
X1067692Y243496D03*
X1074452D03*
X1081212D03*
X1087971D03*
X1094731D03*
X1038015Y234460D03*
X1044774D03*
X1051534D03*
X1071072Y241547D03*
X1077832D03*
X1084591D03*
X1091351D03*
X1038015Y222760D03*
X1044774D03*
X1051534D03*
X1071072Y229847D03*
X1077832D03*
X1084591D03*
X1091351D03*
X1034635Y400209D03*
X1041395D03*
X1048154D03*
X1054914D03*
X1038015Y398260D03*
X1044774D03*
X1051534D03*
X1058294D03*
X1034635Y396309D03*
X1041395D03*
X1048154D03*
X1054914D03*
X1074452Y403396D03*
X1081212D03*
X1087971D03*
X1094731D03*
X1038015Y394359D03*
X1044774D03*
X1051534D03*
X1058294D03*
X1071072Y401447D03*
X1077832D03*
X1084591D03*
X1091351D03*
X1034635Y392410D03*
X1041395D03*
X1048154D03*
X1054914D03*
X1074452Y399496D03*
X1081212D03*
X1087971D03*
X1094731D03*
X1038015Y390460D03*
X1044774D03*
X1051534D03*
X1058294D03*
X1071072Y397546D03*
X1077832D03*
X1084591D03*
X1091351D03*
X1034635Y388509D03*
X1041395D03*
X1048154D03*
X1054914D03*
X1074452Y395597D03*
X1081212D03*
X1087971D03*
X1094731D03*
X1038015Y386560D03*
X1044774D03*
X1051534D03*
X1058294D03*
X1071072Y393647D03*
X1077832D03*
X1084591D03*
X1091351D03*
X1034635Y384609D03*
X1041395D03*
X1048154D03*
X1054914D03*
X1074452Y391696D03*
X1081212D03*
X1087971D03*
X1094731D03*
X1038015Y382660D03*
X1044774D03*
X1051534D03*
X1058294D03*
X1071072Y389747D03*
X1077832D03*
X1084591D03*
X1091351D03*
X1034635Y380709D03*
X1041395D03*
X1048154D03*
X1054914D03*
X1074452Y387796D03*
X1081212D03*
X1087971D03*
X1094731D03*
X1038015Y378760D03*
X1044774D03*
X1051534D03*
X1058294D03*
X1071072Y385847D03*
X1077832D03*
X1084591D03*
X1091351D03*
X1034635Y376809D03*
X1041395D03*
X1048154D03*
X1054914D03*
X1074452Y383896D03*
X1081212D03*
X1087971D03*
X1094731D03*
X1038015Y374860D03*
X1044774D03*
X1051534D03*
X1058294D03*
X1071072Y381947D03*
X1077832D03*
X1084591D03*
X1091351D03*
X1038015Y370959D03*
X1044774D03*
X1051534D03*
X1058294D03*
X1071072Y378047D03*
X1077832D03*
X1084591D03*
X1091351D03*
X1034635Y369010D03*
X1041395D03*
X1048154D03*
X1054914D03*
X1074452Y376096D03*
X1081212D03*
X1087971D03*
X1094731D03*
X1038015Y367060D03*
X1044774D03*
X1051534D03*
X1058294D03*
X1071072Y374146D03*
X1077832D03*
X1084591D03*
X1091351D03*
X1034635Y365109D03*
X1041395D03*
X1048154D03*
X1054914D03*
X1074452Y372197D03*
X1081212D03*
X1087971D03*
X1094731D03*
X1038015Y363160D03*
X1044774D03*
X1051534D03*
X1058294D03*
X1071072Y370247D03*
X1077832D03*
X1084591D03*
X1091351D03*
X1034635Y361209D03*
X1041395D03*
X1048154D03*
X1054914D03*
X1074452Y368296D03*
X1081212D03*
X1087971D03*
X1094731D03*
X1038015Y359260D03*
X1044774D03*
X1051534D03*
X1058294D03*
X1071072Y366347D03*
X1077832D03*
X1084591D03*
X1091351D03*
X1034635Y357309D03*
X1041395D03*
X1048154D03*
X1054914D03*
X1074452Y364396D03*
X1081212D03*
X1087971D03*
X1094731D03*
X1038015Y355360D03*
X1044774D03*
X1051534D03*
X1058294D03*
X1071072Y362447D03*
X1077832D03*
X1084591D03*
X1091351D03*
X1034635Y353409D03*
X1041395D03*
X1048154D03*
X1054914D03*
X1074452Y360496D03*
X1081212D03*
X1087971D03*
X1094731D03*
X1038015Y351460D03*
X1044774D03*
X1051534D03*
X1058294D03*
X1071072Y358547D03*
X1077832D03*
X1084591D03*
X1091351D03*
X1034635Y349509D03*
X1041395D03*
X1048154D03*
X1054914D03*
X1074452Y356596D03*
X1081212D03*
X1087971D03*
X1094731D03*
X1038015Y347560D03*
X1044774D03*
X1051534D03*
X1071072Y354647D03*
X1077832D03*
X1084591D03*
X1091351D03*
X1034635Y345609D03*
X1074452Y352696D03*
X1081212D03*
X1087971D03*
X1094731D03*
X1071072Y350747D03*
X1077832D03*
X1084591D03*
X1091351D03*
X1074452Y348796D03*
X1081212D03*
X1087971D03*
X1094731D03*
X1034635Y372909D03*
X1041395D03*
X1048154D03*
X1054914D03*
X1074452Y379996D03*
X1081212D03*
X1087971D03*
X1094731D03*
X1077832Y405347D03*
X1084591D03*
X1091351D03*
X1098111Y218147D03*
X1104871D03*
X1111631D03*
X1118391D03*
X1125150D03*
X1131910D03*
X1138670D03*
X1145430D03*
X1152190D03*
X1101491Y216196D03*
X1108251D03*
X1115011D03*
X1121771D03*
X1128530D03*
X1135290D03*
X1142050D03*
X1148810D03*
X1155570D03*
X1098111Y214247D03*
X1104871D03*
X1111631D03*
X1118391D03*
X1125150D03*
X1131910D03*
X1138670D03*
X1145430D03*
X1152190D03*
X1101491Y212296D03*
X1108251D03*
X1115011D03*
X1121771D03*
X1128530D03*
X1135290D03*
X1142050D03*
X1148810D03*
X1155570D03*
X1098111Y210346D03*
X1104871D03*
X1111631D03*
X1118391D03*
X1125150D03*
X1131910D03*
X1138670D03*
X1145430D03*
X1152190D03*
X1101491Y208397D03*
X1108251D03*
X1115011D03*
X1121771D03*
X1128530D03*
X1155570D03*
X1098111Y206447D03*
X1104871D03*
X1111631D03*
X1118391D03*
X1125150D03*
X1131910D03*
X1152190D03*
X1101491Y204496D03*
X1108251D03*
X1115011D03*
X1121771D03*
X1128530D03*
X1155570D03*
X1098111Y202547D03*
X1104871D03*
X1111631D03*
X1118391D03*
X1125150D03*
X1131910D03*
X1101491Y239596D03*
X1108251D03*
X1115011D03*
X1121771D03*
X1128530D03*
X1135290D03*
X1142050D03*
X1148810D03*
X1155570D03*
X1098111Y237647D03*
X1104871D03*
X1111631D03*
X1118391D03*
X1125150D03*
X1131910D03*
X1138670D03*
X1145430D03*
X1152190D03*
X1101491Y235696D03*
X1108251D03*
X1115011D03*
X1121771D03*
X1128530D03*
X1135290D03*
X1142050D03*
X1148810D03*
X1155570D03*
X1098111Y233746D03*
X1104871D03*
X1111631D03*
X1118391D03*
X1125150D03*
X1131910D03*
X1138670D03*
X1145430D03*
X1152190D03*
X1101491Y231797D03*
X1108251D03*
X1115011D03*
X1121771D03*
X1128530D03*
X1135290D03*
X1142050D03*
X1148810D03*
X1155570D03*
X1101491Y227896D03*
X1108251D03*
X1115011D03*
X1121771D03*
X1128530D03*
X1135290D03*
X1142050D03*
X1148810D03*
X1155570D03*
X1098111Y225947D03*
X1104871D03*
X1111631D03*
X1118391D03*
X1125150D03*
X1131910D03*
X1138670D03*
X1145430D03*
X1152190D03*
X1101491Y223996D03*
X1108251D03*
X1115011D03*
X1121771D03*
X1128530D03*
X1135290D03*
X1142050D03*
X1148810D03*
X1155570D03*
X1098111Y222047D03*
X1104871D03*
X1111631D03*
X1118391D03*
X1125150D03*
X1131910D03*
X1138670D03*
X1145430D03*
X1152190D03*
X1101491Y220096D03*
X1108251D03*
X1115011D03*
X1121771D03*
X1128530D03*
X1135290D03*
X1142050D03*
X1148810D03*
X1155570D03*
X1121771Y278596D03*
X1128530D03*
X1135290D03*
X1142050D03*
X1148810D03*
X1155570D03*
X1125150Y276646D03*
X1131910D03*
X1138670D03*
X1145430D03*
X1152190D03*
X1121771Y274696D03*
X1128530D03*
X1135290D03*
X1142050D03*
X1148810D03*
X1155570D03*
X1118391Y272747D03*
X1125150D03*
X1131910D03*
X1138670D03*
X1145430D03*
X1152190D03*
X1115011Y270796D03*
X1121771D03*
X1128530D03*
X1135290D03*
X1142050D03*
X1148810D03*
X1155570D03*
X1111631Y268847D03*
X1118391D03*
X1125150D03*
X1131910D03*
X1138670D03*
X1145430D03*
X1152190D03*
X1108251Y266896D03*
X1115011D03*
X1121771D03*
X1128530D03*
X1135290D03*
X1142050D03*
X1148810D03*
X1155570D03*
X1104871Y264947D03*
X1111631D03*
X1118391D03*
X1125150D03*
X1131910D03*
X1138670D03*
X1145430D03*
X1152190D03*
X1101491Y262996D03*
X1108251D03*
X1115011D03*
X1121771D03*
X1128530D03*
X1135290D03*
X1142050D03*
X1148810D03*
X1098111Y261047D03*
X1104871D03*
X1111631D03*
X1118391D03*
X1125150D03*
X1131910D03*
X1138670D03*
X1145430D03*
X1152190D03*
X1101491Y259096D03*
X1108251D03*
X1115011D03*
X1121771D03*
X1128530D03*
X1135290D03*
X1142050D03*
X1148810D03*
X1098111Y257147D03*
X1104871D03*
X1111631D03*
X1118391D03*
X1125150D03*
X1131910D03*
X1138670D03*
X1145430D03*
X1152190D03*
X1101491Y255196D03*
X1108251D03*
X1115011D03*
X1121771D03*
X1128530D03*
X1135290D03*
X1142050D03*
X1148810D03*
X1098111Y253247D03*
X1104871D03*
X1111631D03*
X1118391D03*
X1125150D03*
X1131910D03*
X1138670D03*
X1145430D03*
X1152190D03*
X1101491Y251296D03*
X1108251D03*
X1115011D03*
X1121771D03*
X1128530D03*
X1135290D03*
X1142050D03*
X1148810D03*
X1155570D03*
X1098111Y249347D03*
X1104871D03*
X1111631D03*
X1118391D03*
X1125150D03*
X1131910D03*
X1138670D03*
X1145430D03*
X1152190D03*
X1101491Y247396D03*
X1108251D03*
X1115011D03*
X1121771D03*
X1128530D03*
X1135290D03*
X1142050D03*
X1148810D03*
X1155570D03*
X1098111Y245447D03*
X1104871D03*
X1111631D03*
X1118391D03*
X1125150D03*
X1131910D03*
X1138670D03*
X1145430D03*
X1152190D03*
X1101491Y243496D03*
X1108251D03*
X1115011D03*
X1121771D03*
X1128530D03*
X1135290D03*
X1142050D03*
X1148810D03*
X1155570D03*
X1098111Y241547D03*
X1104871D03*
X1111631D03*
X1118391D03*
X1125150D03*
X1131910D03*
X1138670D03*
X1145430D03*
X1152190D03*
X1098111Y229847D03*
X1104871D03*
X1111631D03*
X1118391D03*
X1125150D03*
X1131910D03*
X1138670D03*
X1145430D03*
X1152190D03*
X1108251Y340996D03*
X1115011D03*
X1121771D03*
X1128530D03*
X1135290D03*
X1142050D03*
X1148810D03*
X1111631Y339047D03*
X1118391D03*
X1125150D03*
X1131910D03*
X1138670D03*
X1145430D03*
X1152190D03*
X1115011Y337096D03*
X1121771D03*
X1128530D03*
X1135290D03*
X1142050D03*
X1148810D03*
X1155570D03*
X1118391Y335147D03*
X1125150D03*
X1131910D03*
X1138670D03*
X1145430D03*
X1152190D03*
X1121771Y333196D03*
X1128530D03*
X1135290D03*
X1142050D03*
X1148810D03*
X1155570D03*
X1125150Y331247D03*
X1131910D03*
X1138670D03*
X1145430D03*
X1152190D03*
X1121771Y329296D03*
X1128530D03*
X1135290D03*
X1142050D03*
X1148810D03*
X1155570D03*
X1125150Y327347D03*
X1131910D03*
X1138670D03*
X1145430D03*
X1152190D03*
X1121771Y325396D03*
X1128530D03*
X1135290D03*
X1142050D03*
X1148810D03*
X1155570D03*
X1125150Y323446D03*
X1131910D03*
X1138670D03*
X1145430D03*
X1152190D03*
X1121771Y321496D03*
X1128530D03*
X1135290D03*
X1142050D03*
X1148810D03*
X1155570D03*
X1125150Y319547D03*
X1131910D03*
X1138670D03*
X1145430D03*
X1152190D03*
X1121771Y317596D03*
X1128530D03*
X1135290D03*
X1142050D03*
X1148810D03*
X1155570D03*
X1125150Y315647D03*
X1131910D03*
X1138670D03*
X1145430D03*
X1152190D03*
X1121771Y313696D03*
X1128530D03*
X1135290D03*
X1142050D03*
X1148810D03*
X1155570D03*
X1125150Y311747D03*
X1131910D03*
X1138670D03*
X1145430D03*
X1152190D03*
X1121771Y309797D03*
X1128530D03*
X1135290D03*
X1142050D03*
X1148810D03*
X1155570D03*
X1125150Y307847D03*
X1131910D03*
X1138670D03*
X1145430D03*
X1152190D03*
X1121771Y305896D03*
X1128530D03*
X1135290D03*
X1142050D03*
X1148810D03*
X1155570D03*
X1125150Y303947D03*
X1131910D03*
X1138670D03*
X1145430D03*
X1152190D03*
X1121771Y301996D03*
X1128530D03*
X1135290D03*
X1142050D03*
X1148810D03*
X1155570D03*
X1125150Y300047D03*
X1131910D03*
X1138670D03*
X1145430D03*
X1152190D03*
X1121771Y298096D03*
X1128530D03*
X1135290D03*
X1142050D03*
X1148810D03*
X1155570D03*
X1125150Y296147D03*
X1131910D03*
X1138670D03*
X1145430D03*
X1152190D03*
X1121771Y294196D03*
X1128530D03*
X1135290D03*
X1142050D03*
X1148810D03*
X1155570D03*
X1125150Y292247D03*
X1131910D03*
X1138670D03*
X1145430D03*
X1152190D03*
X1121771Y290296D03*
X1128530D03*
X1135290D03*
X1142050D03*
X1148810D03*
X1155570D03*
X1125150Y288347D03*
X1131910D03*
X1138670D03*
X1145430D03*
X1152190D03*
X1121771Y286396D03*
X1128530D03*
X1135290D03*
X1142050D03*
X1148810D03*
X1155570D03*
X1125150Y284447D03*
X1131910D03*
X1138670D03*
X1145430D03*
X1152190D03*
X1121771Y282496D03*
X1128530D03*
X1135290D03*
X1142050D03*
X1148810D03*
X1155570D03*
X1125150Y280547D03*
X1131910D03*
X1138670D03*
X1145430D03*
X1152190D03*
X1101491Y403396D03*
X1108251D03*
X1115011D03*
X1121771D03*
X1128530D03*
X1135290D03*
X1098111Y401447D03*
X1104871D03*
X1111631D03*
X1118391D03*
X1125150D03*
X1131910D03*
X1138670D03*
X1101491Y399496D03*
X1108251D03*
X1115011D03*
X1121771D03*
X1128530D03*
X1135290D03*
X1142050D03*
X1098111Y397546D03*
X1104871D03*
X1111631D03*
X1118391D03*
X1125150D03*
X1131910D03*
X1138670D03*
X1145430D03*
X1152190D03*
X1101491Y395597D03*
X1108251D03*
X1115011D03*
X1121771D03*
X1128530D03*
X1135290D03*
X1142050D03*
X1148810D03*
X1155570D03*
X1098111Y393647D03*
X1104871D03*
X1111631D03*
X1118391D03*
X1125150D03*
X1131910D03*
X1138670D03*
X1145430D03*
X1152190D03*
X1101491Y391696D03*
X1108251D03*
X1115011D03*
X1121771D03*
X1128530D03*
X1135290D03*
X1142050D03*
X1148810D03*
X1155570D03*
X1098111Y389747D03*
X1104871D03*
X1111631D03*
X1118391D03*
X1125150D03*
X1131910D03*
X1138670D03*
X1145430D03*
X1152190D03*
X1101491Y387796D03*
X1108251D03*
X1115011D03*
X1121771D03*
X1128530D03*
X1135290D03*
X1142050D03*
X1148810D03*
X1155570D03*
X1098111Y385847D03*
X1104871D03*
X1111631D03*
X1118391D03*
X1125150D03*
X1131910D03*
X1138670D03*
X1145430D03*
X1152190D03*
X1101491Y383896D03*
X1108251D03*
X1115011D03*
X1121771D03*
X1128530D03*
X1135290D03*
X1142050D03*
X1148810D03*
X1155570D03*
X1098111Y381947D03*
X1104871D03*
X1111631D03*
X1118391D03*
X1125150D03*
X1131910D03*
X1138670D03*
X1145430D03*
X1152190D03*
X1098111Y378047D03*
X1104871D03*
X1111631D03*
X1118391D03*
X1125150D03*
X1131910D03*
X1138670D03*
X1145430D03*
X1152190D03*
X1101491Y376096D03*
X1108251D03*
X1115011D03*
X1121771D03*
X1128530D03*
X1135290D03*
X1142050D03*
X1148810D03*
X1155570D03*
X1098111Y374146D03*
X1104871D03*
X1111631D03*
X1118391D03*
X1125150D03*
X1131910D03*
X1138670D03*
X1145430D03*
X1152190D03*
X1101491Y372197D03*
X1108251D03*
X1115011D03*
X1121771D03*
X1128530D03*
X1135290D03*
X1142050D03*
X1148810D03*
X1155570D03*
X1098111Y370247D03*
X1104871D03*
X1111631D03*
X1118391D03*
X1125150D03*
X1131910D03*
X1138670D03*
X1145430D03*
X1152190D03*
X1101491Y368296D03*
X1108251D03*
X1115011D03*
X1121771D03*
X1128530D03*
X1135290D03*
X1142050D03*
X1148810D03*
X1155570D03*
X1098111Y366347D03*
X1104871D03*
X1111631D03*
X1118391D03*
X1125150D03*
X1131910D03*
X1138670D03*
X1145430D03*
X1152190D03*
X1101491Y364396D03*
X1108251D03*
X1115011D03*
X1121771D03*
X1128530D03*
X1135290D03*
X1142050D03*
X1148810D03*
X1155570D03*
X1098111Y362447D03*
X1104871D03*
X1111631D03*
X1118391D03*
X1125150D03*
X1131910D03*
X1138670D03*
X1145430D03*
X1152190D03*
X1101491Y360496D03*
X1108251D03*
X1115011D03*
X1121771D03*
X1128530D03*
X1135290D03*
X1142050D03*
X1148810D03*
X1155570D03*
X1098111Y358547D03*
X1104871D03*
X1111631D03*
X1118391D03*
X1125150D03*
X1131910D03*
X1138670D03*
X1145430D03*
X1152190D03*
X1101491Y356596D03*
X1108251D03*
X1115011D03*
X1121771D03*
X1128530D03*
X1135290D03*
X1142050D03*
X1148810D03*
X1155570D03*
X1098111Y354647D03*
X1104871D03*
X1111631D03*
X1118391D03*
X1125150D03*
X1131910D03*
X1138670D03*
X1145430D03*
X1152190D03*
X1101491Y352696D03*
X1108251D03*
X1115011D03*
X1121771D03*
X1128530D03*
X1135290D03*
X1142050D03*
X1148810D03*
X1155570D03*
X1098111Y350747D03*
X1104871D03*
X1111631D03*
X1118391D03*
X1125150D03*
X1131910D03*
X1138670D03*
X1145430D03*
X1152190D03*
X1101491Y348796D03*
X1108251D03*
X1115011D03*
X1121771D03*
X1128530D03*
X1135290D03*
X1142050D03*
X1148810D03*
X1098111Y346847D03*
X1104871D03*
X1111631D03*
X1118391D03*
X1125150D03*
X1131910D03*
X1138670D03*
X1145430D03*
X1152190D03*
X1101491Y344896D03*
X1108251D03*
X1115011D03*
X1121771D03*
X1128530D03*
X1135290D03*
X1142050D03*
X1148810D03*
X1104871Y342947D03*
X1111631D03*
X1118391D03*
X1125150D03*
X1131910D03*
X1138670D03*
X1145430D03*
X1152190D03*
X1101491Y379996D03*
X1108251D03*
X1115011D03*
X1121771D03*
X1128530D03*
X1135290D03*
X1142050D03*
X1148810D03*
X1155570D03*
X1098111Y405347D03*
X1104871D03*
X1111631D03*
X1118391D03*
X1125150D03*
X1131910D03*
X1185989Y218147D03*
X1192749D03*
X1199509D03*
X1206269D03*
X1158950D03*
X1165710D03*
X1172469D03*
X1179229D03*
X1182609Y216196D03*
X1189369D03*
X1196129D03*
X1202889D03*
X1162330D03*
X1169089D03*
X1175849D03*
X1209649D03*
X1185989Y214247D03*
X1192749D03*
X1199509D03*
X1206269D03*
X1158950D03*
X1165710D03*
X1172469D03*
X1179229D03*
X1182609Y212296D03*
X1189369D03*
X1196129D03*
X1202889D03*
X1162330D03*
X1169089D03*
X1175849D03*
X1185989Y210346D03*
X1192749D03*
X1199509D03*
X1206269D03*
X1158950D03*
X1165710D03*
X1172469D03*
X1179229D03*
X1182609Y208397D03*
X1189369D03*
X1196129D03*
X1202889D03*
X1162330D03*
X1169089D03*
X1175849D03*
X1185989Y206447D03*
X1192749D03*
X1199509D03*
X1158950D03*
X1165710D03*
X1172469D03*
X1179229D03*
X1182609Y204496D03*
X1189369D03*
X1196129D03*
X1202889D03*
X1162330D03*
X1169089D03*
X1175849D03*
X1185989Y202547D03*
X1192749D03*
X1199509D03*
X1158950D03*
X1165710D03*
X1172469D03*
X1179229D03*
X1182609Y239596D03*
X1189369D03*
X1196129D03*
X1202889D03*
X1162330D03*
X1169089D03*
X1175849D03*
X1209649D03*
X1185989Y237647D03*
X1192749D03*
X1199509D03*
X1206269D03*
X1158950D03*
X1165710D03*
X1172469D03*
X1179229D03*
X1182609Y235696D03*
X1189369D03*
X1196129D03*
X1202889D03*
X1162330D03*
X1169089D03*
X1175849D03*
X1209649D03*
X1185989Y233746D03*
X1192749D03*
X1199509D03*
X1206269D03*
X1158950D03*
X1165710D03*
X1172469D03*
X1179229D03*
X1182609Y231797D03*
X1189369D03*
X1196129D03*
X1202889D03*
X1162330D03*
X1169089D03*
X1175849D03*
X1209649D03*
X1182609Y227896D03*
X1189369D03*
X1196129D03*
X1202889D03*
X1162330D03*
X1169089D03*
X1175849D03*
X1209649D03*
X1185989Y225947D03*
X1192749D03*
X1199509D03*
X1206269D03*
X1158950D03*
X1165710D03*
X1172469D03*
X1179229D03*
X1182609Y223996D03*
X1189369D03*
X1196129D03*
X1202889D03*
X1162330D03*
X1169089D03*
X1175849D03*
X1209649D03*
X1185989Y222047D03*
X1192749D03*
X1199509D03*
X1206269D03*
X1158950D03*
X1165710D03*
X1172469D03*
X1179229D03*
X1182609Y220096D03*
X1189369D03*
X1196129D03*
X1202889D03*
X1162330D03*
X1169089D03*
X1175849D03*
X1209649D03*
X1182609Y278596D03*
X1189369D03*
X1196129D03*
X1202889D03*
X1162330D03*
X1169089D03*
X1175849D03*
X1185989Y276646D03*
X1192749D03*
X1199509D03*
X1206269D03*
X1158950D03*
X1165710D03*
X1172469D03*
X1179229D03*
X1182609Y274696D03*
X1189369D03*
X1196129D03*
X1202889D03*
X1162330D03*
X1169089D03*
X1175849D03*
X1209649D03*
X1185989Y272747D03*
X1192749D03*
X1199509D03*
X1206269D03*
X1158950D03*
X1165710D03*
X1172469D03*
X1179229D03*
X1182609Y270796D03*
X1189369D03*
X1196129D03*
X1202889D03*
X1162330D03*
X1169089D03*
X1175849D03*
X1209649D03*
X1185989Y268847D03*
X1192749D03*
X1199509D03*
X1206269D03*
X1158950D03*
X1165710D03*
X1172469D03*
X1179229D03*
X1182609Y266896D03*
X1189369D03*
X1196129D03*
X1202889D03*
X1169089D03*
X1175849D03*
X1209649D03*
X1185989Y264947D03*
X1192749D03*
X1199509D03*
X1206269D03*
X1165710D03*
X1172469D03*
X1179229D03*
X1182609Y262996D03*
X1189369D03*
X1196129D03*
X1202889D03*
X1169089D03*
X1175849D03*
X1209649D03*
X1185989Y261047D03*
X1192749D03*
X1199509D03*
X1206269D03*
X1165710D03*
X1172469D03*
X1179229D03*
X1182609Y259096D03*
X1189369D03*
X1196129D03*
X1202889D03*
X1169089D03*
X1175849D03*
X1209649D03*
X1185989Y257147D03*
X1192749D03*
X1199509D03*
X1206269D03*
X1165710D03*
X1172469D03*
X1179229D03*
X1182609Y255196D03*
X1189369D03*
X1196129D03*
X1202889D03*
X1162330D03*
X1169089D03*
X1175849D03*
X1209649D03*
X1185989Y253247D03*
X1192749D03*
X1199509D03*
X1206269D03*
X1158950D03*
X1165710D03*
X1172469D03*
X1179229D03*
X1182609Y251296D03*
X1189369D03*
X1196129D03*
X1202889D03*
X1162330D03*
X1169089D03*
X1175849D03*
X1209649D03*
X1185989Y249347D03*
X1192749D03*
X1199509D03*
X1206269D03*
X1158950D03*
X1165710D03*
X1172469D03*
X1179229D03*
X1182609Y247396D03*
X1189369D03*
X1196129D03*
X1202889D03*
X1162330D03*
X1169089D03*
X1175849D03*
X1209649D03*
X1185989Y245447D03*
X1192749D03*
X1199509D03*
X1206269D03*
X1158950D03*
X1165710D03*
X1172469D03*
X1179229D03*
X1182609Y243496D03*
X1189369D03*
X1196129D03*
X1202889D03*
X1162330D03*
X1169089D03*
X1175849D03*
X1209649D03*
X1185989Y241547D03*
X1192749D03*
X1199509D03*
X1206269D03*
X1158950D03*
X1165710D03*
X1172469D03*
X1179229D03*
X1185989Y229847D03*
X1192749D03*
X1199509D03*
X1206269D03*
X1158950D03*
X1165710D03*
X1172469D03*
X1179229D03*
X1182609Y340996D03*
X1189369D03*
X1196129D03*
X1202889D03*
X1162330D03*
X1169089D03*
X1175849D03*
X1209649D03*
X1185989Y339047D03*
X1192749D03*
X1199509D03*
X1206269D03*
X1158950D03*
X1165710D03*
X1172469D03*
X1179229D03*
X1182609Y337096D03*
X1189369D03*
X1196129D03*
X1202889D03*
X1162330D03*
X1169089D03*
X1175849D03*
X1209649D03*
X1185989Y335147D03*
X1192749D03*
X1199509D03*
X1206269D03*
X1158950D03*
X1165710D03*
X1172469D03*
X1179229D03*
X1182609Y333196D03*
X1189369D03*
X1196129D03*
X1202889D03*
X1162330D03*
X1169089D03*
X1175849D03*
X1209649D03*
X1185989Y331247D03*
X1192749D03*
X1199509D03*
X1206269D03*
X1158950D03*
X1165710D03*
X1172469D03*
X1179229D03*
X1182609Y329296D03*
X1189369D03*
X1196129D03*
X1202889D03*
X1162330D03*
X1169089D03*
X1175849D03*
X1185989Y327347D03*
X1192749D03*
X1199509D03*
X1206269D03*
X1158950D03*
X1165710D03*
X1172469D03*
X1179229D03*
X1182609Y325396D03*
X1189369D03*
X1196129D03*
X1202889D03*
X1162330D03*
X1169089D03*
X1175849D03*
X1185989Y323446D03*
X1192749D03*
X1199509D03*
X1206269D03*
X1158950D03*
X1165710D03*
X1172469D03*
X1179229D03*
X1182609Y321496D03*
X1189369D03*
X1196129D03*
X1202889D03*
X1162330D03*
X1169089D03*
X1175849D03*
X1185989Y319547D03*
X1192749D03*
X1199509D03*
X1206269D03*
X1158950D03*
X1165710D03*
X1172469D03*
X1179229D03*
X1182609Y317596D03*
X1189369D03*
X1196129D03*
X1202889D03*
X1162330D03*
X1169089D03*
X1175849D03*
X1185989Y315647D03*
X1192749D03*
X1199509D03*
X1158950D03*
X1165710D03*
X1172469D03*
X1179229D03*
X1182609Y313696D03*
X1189369D03*
X1196129D03*
X1202889D03*
X1162330D03*
X1169089D03*
X1175849D03*
X1185989Y311747D03*
X1192749D03*
X1199509D03*
X1158950D03*
X1165710D03*
X1172469D03*
X1179229D03*
X1182609Y309797D03*
X1189369D03*
X1196129D03*
X1202889D03*
X1162330D03*
X1169089D03*
X1175849D03*
X1185989Y307847D03*
X1192749D03*
X1199509D03*
X1158950D03*
X1165710D03*
X1172469D03*
X1179229D03*
X1182609Y305896D03*
X1189369D03*
X1196129D03*
X1202889D03*
X1162330D03*
X1169089D03*
X1175849D03*
X1185989Y303947D03*
X1192749D03*
X1199509D03*
X1158950D03*
X1165710D03*
X1172469D03*
X1179229D03*
X1182609Y301996D03*
X1189369D03*
X1196129D03*
X1202889D03*
X1162330D03*
X1169089D03*
X1175849D03*
X1185989Y300047D03*
X1192749D03*
X1199509D03*
X1158950D03*
X1165710D03*
X1172469D03*
X1179229D03*
X1182609Y298096D03*
X1189369D03*
X1196129D03*
X1202889D03*
X1162330D03*
X1169089D03*
X1175849D03*
X1185989Y296147D03*
X1192749D03*
X1199509D03*
X1158950D03*
X1165710D03*
X1172469D03*
X1179229D03*
X1182609Y294196D03*
X1189369D03*
X1196129D03*
X1202889D03*
X1162330D03*
X1169089D03*
X1175849D03*
X1185989Y292247D03*
X1192749D03*
X1199509D03*
X1158950D03*
X1165710D03*
X1172469D03*
X1179229D03*
X1182609Y290296D03*
X1189369D03*
X1196129D03*
X1202889D03*
X1162330D03*
X1169089D03*
X1175849D03*
X1185989Y288347D03*
X1192749D03*
X1199509D03*
X1158950D03*
X1165710D03*
X1172469D03*
X1179229D03*
X1182609Y286396D03*
X1189369D03*
X1196129D03*
X1202889D03*
X1162330D03*
X1169089D03*
X1175849D03*
X1185989Y284447D03*
X1192749D03*
X1199509D03*
X1206269D03*
X1158950D03*
X1165710D03*
X1172469D03*
X1179229D03*
X1182609Y282496D03*
X1189369D03*
X1196129D03*
X1202889D03*
X1162330D03*
X1169089D03*
X1175849D03*
X1185989Y280547D03*
X1192749D03*
X1199509D03*
X1206269D03*
X1158950D03*
X1165710D03*
X1172469D03*
X1179229D03*
X1182609Y403396D03*
X1189369D03*
X1196129D03*
X1162330D03*
X1169089D03*
X1175849D03*
X1185989Y401447D03*
X1192749D03*
X1199509D03*
X1158950D03*
X1165710D03*
X1172469D03*
X1179229D03*
X1182609Y399496D03*
X1189369D03*
X1196129D03*
X1202889D03*
X1162330D03*
X1169089D03*
X1175849D03*
X1185989Y397546D03*
X1192749D03*
X1199509D03*
X1158950D03*
X1165710D03*
X1172469D03*
X1179229D03*
X1182609Y395597D03*
X1189369D03*
X1196129D03*
X1202889D03*
X1162330D03*
X1169089D03*
X1175849D03*
X1185989Y393647D03*
X1192749D03*
X1199509D03*
X1206269D03*
X1158950D03*
X1165710D03*
X1172469D03*
X1179229D03*
X1182609Y391696D03*
X1189369D03*
X1196129D03*
X1202889D03*
X1162330D03*
X1169089D03*
X1175849D03*
X1185989Y389747D03*
X1192749D03*
X1199509D03*
X1206269D03*
X1158950D03*
X1165710D03*
X1172469D03*
X1179229D03*
X1182609Y387796D03*
X1189369D03*
X1196129D03*
X1202889D03*
X1162330D03*
X1169089D03*
X1175849D03*
X1185989Y385847D03*
X1192749D03*
X1199509D03*
X1206269D03*
X1158950D03*
X1165710D03*
X1172469D03*
X1179229D03*
X1182609Y383896D03*
X1189369D03*
X1196129D03*
X1202889D03*
X1162330D03*
X1169089D03*
X1175849D03*
X1185989Y381947D03*
X1192749D03*
X1199509D03*
X1206269D03*
X1158950D03*
X1165710D03*
X1172469D03*
X1179229D03*
X1185989Y378047D03*
X1192749D03*
X1199509D03*
X1206269D03*
X1158950D03*
X1165710D03*
X1172469D03*
X1179229D03*
X1182609Y376096D03*
X1189369D03*
X1196129D03*
X1202889D03*
X1162330D03*
X1169089D03*
X1175849D03*
X1185989Y374146D03*
X1192749D03*
X1199509D03*
X1206269D03*
X1158950D03*
X1165710D03*
X1172469D03*
X1179229D03*
X1182609Y372197D03*
X1189369D03*
X1196129D03*
X1202889D03*
X1162330D03*
X1169089D03*
X1175849D03*
X1185989Y370247D03*
X1192749D03*
X1199509D03*
X1206269D03*
X1158950D03*
X1165710D03*
X1172469D03*
X1179229D03*
X1182609Y368296D03*
X1189369D03*
X1196129D03*
X1202889D03*
X1162330D03*
X1169089D03*
X1175849D03*
X1185989Y366347D03*
X1192749D03*
X1199509D03*
X1206269D03*
X1158950D03*
X1165710D03*
X1172469D03*
X1179229D03*
X1182609Y364396D03*
X1189369D03*
X1196129D03*
X1202889D03*
X1162330D03*
X1169089D03*
X1175849D03*
X1185989Y362447D03*
X1192749D03*
X1199509D03*
X1206269D03*
X1158950D03*
X1165710D03*
X1172469D03*
X1179229D03*
X1182609Y360496D03*
X1189369D03*
X1196129D03*
X1202889D03*
X1162330D03*
X1169089D03*
X1175849D03*
X1209649D03*
X1185989Y358547D03*
X1192749D03*
X1199509D03*
X1206269D03*
X1158950D03*
X1165710D03*
X1172469D03*
X1179229D03*
X1182609Y356596D03*
X1189369D03*
X1196129D03*
X1202889D03*
X1162330D03*
X1169089D03*
X1175849D03*
X1209649D03*
X1185989Y354647D03*
X1192749D03*
X1199509D03*
X1206269D03*
X1158950D03*
X1165710D03*
X1172469D03*
X1179229D03*
X1182609Y352696D03*
X1189369D03*
X1196129D03*
X1202889D03*
X1169089D03*
X1175849D03*
X1209649D03*
X1185989Y350747D03*
X1192749D03*
X1199509D03*
X1206269D03*
X1165710D03*
X1172469D03*
X1179229D03*
X1182609Y348796D03*
X1189369D03*
X1196129D03*
X1202889D03*
X1169089D03*
X1175849D03*
X1209649D03*
X1185989Y346847D03*
X1192749D03*
X1199509D03*
X1206269D03*
X1165710D03*
X1172469D03*
X1179229D03*
X1182609Y344896D03*
X1189369D03*
X1196129D03*
X1202889D03*
X1169089D03*
X1175849D03*
X1209649D03*
X1185989Y342947D03*
X1192749D03*
X1199509D03*
X1206269D03*
X1165710D03*
X1172469D03*
X1179229D03*
X1182609Y379996D03*
X1189369D03*
X1196129D03*
X1202889D03*
X1162330D03*
X1169089D03*
X1175849D03*
X1185989Y405347D03*
X1192749D03*
X1158950D03*
X1165710D03*
X1172469D03*
X1179229D03*
G54D78*
X78395Y288750D03*
X76425D03*
X74455D03*
X72485D03*
X70515D03*
X68545D03*
X66575D03*
X64605D03*
G54D199*
X1466733Y591553D03*
X1502030Y597154D03*
G54D97*
X348000Y13200D03*
X353500D03*
X343142D03*
X337642D03*
X330142D03*
X324642D03*
X317942D03*
X312442D03*
X348000Y51000D03*
X353500D03*
X343142D03*
X337642D03*
X330142D03*
X324642D03*
X317942D03*
X312442D03*
X307693Y495595D03*
X313193D03*
X348000Y552000D03*
X353500D03*
X343142D03*
X337642D03*
X330142D03*
X324642D03*
X317872D03*
X312372D03*
X348000Y589800D03*
X353500D03*
X343142D03*
X337642D03*
X330142D03*
X324642D03*
X317942D03*
X312442D03*
X360792Y13078D03*
X366292D03*
X411650Y13200D03*
X417150D03*
X399200D03*
X404700D03*
X361178Y50492D03*
X366678D03*
X411650Y51000D03*
X417150D03*
X399200D03*
X404700D03*
X360292Y589800D03*
X365792D03*
X411650Y552000D03*
X417150D03*
X399200D03*
X404700D03*
X366692D03*
X361192D03*
X411650Y589800D03*
X417150D03*
X399200D03*
X404700D03*
X437008Y13200D03*
X442508D03*
X424650D03*
X430150D03*
X437008Y51000D03*
X442508D03*
X424650D03*
X430150D03*
X437008Y552000D03*
X442508D03*
X424650D03*
X430150D03*
X437008Y589800D03*
X442508D03*
X424650D03*
X430150D03*
X967550Y13200D03*
X962050D03*
X967550Y51000D03*
X962050D03*
X957301Y495595D03*
X962801D03*
X967450Y552000D03*
X961950D03*
X967450Y589800D03*
X961950D03*
X1010400Y13078D03*
X1015900D03*
X997608Y13200D03*
X1003108D03*
X992750D03*
X987250D03*
X979750D03*
X974250D03*
X1010900Y50800D03*
X1016400D03*
X997608Y51000D03*
X1003108D03*
X992750D03*
X987250D03*
X979750D03*
X974250D03*
X1009700Y589500D03*
X1015200D03*
X1016000Y551700D03*
X1010500D03*
X997608Y552000D03*
X1003108D03*
X992750D03*
X987250D03*
X979850D03*
X974350D03*
X997608Y589800D03*
X1003108D03*
X992750D03*
X987250D03*
X979750D03*
X974250D03*
X1086616Y13200D03*
X1092116D03*
X1074258D03*
X1079758D03*
X1061258D03*
X1066758D03*
X1048808D03*
X1054308D03*
X1086616Y51000D03*
X1092116D03*
X1074258D03*
X1079758D03*
X1061258D03*
X1066758D03*
X1048808D03*
X1054308D03*
X1086616Y552000D03*
X1092116D03*
X1074258D03*
X1079758D03*
X1061258D03*
X1066758D03*
X1048808D03*
X1054308D03*
X1086616Y589800D03*
X1092116D03*
X1074258D03*
X1079758D03*
X1061258D03*
X1066758D03*
X1048808D03*
X1054308D03*
G54D298*
X1899900Y206900D03*
G54D88*
X60512Y467244D03*
X1891086Y592105D03*
X1904100Y493000D03*
X1968000Y568500D03*
Y554500D03*
Y590000D03*
Y576000D03*
Y597500D03*
Y611500D03*
G54D79*
X62250Y291105D03*
Y293075D03*
Y295045D03*
Y297015D03*
Y298985D03*
Y300955D03*
Y302925D03*
Y304895D03*
G54D289*
X1851250Y584622D03*
Y576748D03*
Y568874D03*
G54D299*
X1898800Y195344D03*
G54D98*
X306092Y100800D03*
X309981Y104689D03*
X955700Y100800D03*
X959589Y104689D03*
G54D89*
X53839Y427982D03*
X64839Y435856D03*
X53839Y443730D03*
G54D99*
X331592Y114748D03*
X335792Y104069D03*
X324692Y114882D03*
X349692Y108643D03*
X337892Y113956D03*
X660128Y296830D03*
X726287Y258979D03*
X981200Y115148D03*
X985400Y104069D03*
X974300Y115182D03*
X999300Y108743D03*
X987500Y113956D03*
X1119700Y116492D03*
M02*
